FILE_TYPE = MACRO_DRAWING;
SET COLOR_WIRE YELLOW;
SET COLOR_PROP ORANGE;
SET COLOR_DOT WHITE;
SET COLOR_ARC YELLOW;
SET COLOR_BODY GREEN;
SET COLOR_NOTE PURPLE;
SET PROP_DISPLAY VALUE;
SET PAGE_NUMBER P289;
FORCEADD HOLE..1
(3100 1175);
FORCEPROP 1 LAST PART_NUMBER TMP-Q_HOLE78
J 0
(2975 1355);
DISPLAY 0.723404 (2975 1355);
PAINT GREEN (2975 1355);
DISPLAY INVISIBLE (2975 1355);
FORCEPROP 1 LAST MATERIAL EMPTY
J 0
(2975 1310);
DISPLAY 0.723404 (2975 1310);
PAINT GREEN (2975 1310);
FORCEPROP 2 LAST PACK_TYPE TH
J 0
(2975 1450);
DISPLAY 1.021277 (2975 1450);
FORCEPROP 1 LAST $LOCATION H36
J 0
(2975 1410);
DISPLAY 0.723404 (2975 1410);
PAINT GREEN (2975 1410);
FORCEPROP 2 LASTPIN (2900 1200) $PN 1
J 2
(2890 1210);
DISPLAY 0.808511 (2890 1210);
FORCEPROP 1 LAST PATH I10
J 0
(3150 1305);
DISPLAY 0.723404 (3150 1305);
PAINT GREEN (3150 1305);
DISPLAY INVISIBLE (3150 1305);
FORCEPROP 1 LAST NEEDS_NO_SIZE TRUE
J 0
(3100 1175);
DISPLAY 0.468085 (3100 1175);
PAINT GREEN (3100 1175);
DISPLAY INVISIBLE (3100 1175);
FORCEPROP 2 LAST CDS_LIB pure_quanta
J 0
(3100 1175);
PAINT MONO (3100 1175);
DISPLAY INVISIBLE (3100 1175);
FORCEPROP 2 LAST CDS_LOCATION H36
J 0
(2975 1500);
DISPLAY 1.021277 (2975 1500);
DISPLAY INVISIBLE (2975 1500);
FORCEPROP 2 LAST $SEC 1
J 0
(2975 1500);
DISPLAY 0.680851 (2975 1500);
PAINT MONO (2975 1500);
DISPLAY INVISIBLE (2975 1500);
FORCEPROP 2 LAST CDS_SEC 1
J 0
(2975 1500);
DISPLAY 1.021277 (2975 1500);
DISPLAY INVISIBLE (2975 1500);
FORCEADD UNIVERSAL_GND..1
(500 900);
FORCEPROP 3 LASTPIN (500 950) SIG_NAME GND\g
J 0
(510 960);
DISPLAY 0.659574 (510 960);
PAINT MONO (510 960);
DISPLAY INVISIBLE (510 960);
FORCEPROP 2 LAST CDS_LIB logical_power
J 0
(500 900);
DISPLAY INVISIBLE (500 900);
FORCEPROP 1 LAST PATH I100
J 0
(575 900);
DISPLAY 0.872340 (575 900);
PAINT AQUA (575 900);
DISPLAY INVISIBLE (575 900);
FORCEPROP 1 LAST HDL_POWER GND
J 1
(525 825);
DISPLAY 0.872340 (525 825);
PAINT GREEN (525 825);
DISPLAY INVISIBLE (525 825);
FORCEADD UNIVERSAL_GND..1
(1050 900);
FORCEPROP 3 LASTPIN (1050 950) SIG_NAME GND\g
J 0
(1060 960);
DISPLAY 0.659574 (1060 960);
PAINT MONO (1060 960);
DISPLAY INVISIBLE (1060 960);
FORCEPROP 2 LAST CDS_LIB logical_power
J 0
(1050 900);
DISPLAY INVISIBLE (1050 900);
FORCEPROP 1 LAST PATH I101
J 0
(1125 900);
DISPLAY 0.872340 (1125 900);
PAINT AQUA (1125 900);
DISPLAY INVISIBLE (1125 900);
FORCEPROP 1 LAST HDL_POWER GND
J 1
(1075 825);
DISPLAY 0.872340 (1075 825);
PAINT GREEN (1075 825);
DISPLAY INVISIBLE (1075 825);
FORCEADD HOLE..1
(775 2275);
FORCEPROP 1 LAST PART_NUMBER DUMMY50
J 0
(650 2455);
DISPLAY 0.723404 (650 2455);
PAINT GREEN (650 2455);
DISPLAY INVISIBLE (650 2455);
FORCEPROP 2 LAST PACK_TYPE TH
J 0
(650 2550);
DISPLAY 1.021277 (650 2550);
FORCEPROP 1 LAST MATERIAL EMPTY
J 0
(650 2410);
DISPLAY 0.723404 (650 2410);
PAINT GREEN (650 2410);
FORCEPROP 1 LAST $LOCATION H28
J 0
(650 2510);
DISPLAY 0.723404 (650 2510);
PAINT GREEN (650 2510);
FORCEPROP 2 LASTPIN (575 2300) $PN 1
J 2
(565 2310);
DISPLAY 0.808511 (565 2310);
FORCEPROP 1 LAST PATH I11
J 0
(825 2405);
DISPLAY 0.723404 (825 2405);
PAINT GREEN (825 2405);
DISPLAY INVISIBLE (825 2405);
FORCEPROP 2 LAST CDS_LIB pure_quanta
J 0
(775 2275);
PAINT MONO (775 2275);
DISPLAY INVISIBLE (775 2275);
FORCEPROP 1 LAST NEEDS_NO_SIZE TRUE
J 0
(775 2275);
DISPLAY 0.468085 (775 2275);
PAINT GREEN (775 2275);
DISPLAY INVISIBLE (775 2275);
FORCEPROP 2 LAST CDS_LOCATION H28
J 0
(650 2600);
DISPLAY 1.021277 (650 2600);
DISPLAY INVISIBLE (650 2600);
FORCEPROP 2 LAST $SEC 1
J 0
(650 2600);
DISPLAY 0.680851 (650 2600);
PAINT MONO (650 2600);
DISPLAY INVISIBLE (650 2600);
FORCEPROP 2 LAST CDS_SEC 1
J 0
(650 2600);
DISPLAY 1.021277 (650 2600);
DISPLAY INVISIBLE (650 2600);
FORCEADD HOLE..1
(275 2275);
FORCEPROP 1 LAST PART_NUMBER DUMMY50
J 0
(150 2455);
DISPLAY 0.723404 (150 2455);
PAINT GREEN (150 2455);
DISPLAY INVISIBLE (150 2455);
FORCEPROP 1 LAST MATERIAL EMPTY
J 0
(150 2410);
DISPLAY 0.723404 (150 2410);
PAINT GREEN (150 2410);
FORCEPROP 2 LAST PACK_TYPE TH
J 0
(150 2550);
DISPLAY 1.021277 (150 2550);
FORCEPROP 1 LAST $LOCATION H27
J 0
(150 2510);
DISPLAY 0.723404 (150 2510);
PAINT GREEN (150 2510);
FORCEPROP 2 LASTPIN (75 2300) $PN 1
J 2
(65 2310);
DISPLAY 0.808511 (65 2310);
FORCEPROP 1 LAST PATH I12
J 0
(325 2405);
DISPLAY 0.723404 (325 2405);
PAINT GREEN (325 2405);
DISPLAY INVISIBLE (325 2405);
FORCEPROP 2 LAST CDS_LIB pure_quanta
J 0
(275 2275);
PAINT MONO (275 2275);
DISPLAY INVISIBLE (275 2275);
FORCEPROP 1 LAST NEEDS_NO_SIZE TRUE
J 0
(275 2275);
DISPLAY 0.468085 (275 2275);
PAINT GREEN (275 2275);
DISPLAY INVISIBLE (275 2275);
FORCEPROP 2 LAST CDS_LOCATION H27
J 0
(150 2600);
DISPLAY 1.021277 (150 2600);
DISPLAY INVISIBLE (150 2600);
FORCEPROP 2 LAST $SEC 1
J 0
(150 2600);
DISPLAY 0.680851 (150 2600);
PAINT MONO (150 2600);
DISPLAY INVISIBLE (150 2600);
FORCEPROP 2 LAST CDS_SEC 1
J 0
(150 2600);
DISPLAY 1.021277 (150 2600);
DISPLAY INVISIBLE (150 2600);
FORCEADD HOLE..1
(-2475 4400);
FORCEPROP 1 LAST PART_NUMBER HOLE596
J 0
(-2600 4580);
DISPLAY 0.723404 (-2600 4580);
PAINT GREEN (-2600 4580);
DISPLAY INVISIBLE (-2600 4580);
FORCEPROP 2 LAST PACK_TYPE TH
J 0
(-2625 4875);
DISPLAY 1.021277 (-2625 4875);
FORCEPROP 1 LAST MATERIAL EMPTY
J 0
(-2600 4535);
DISPLAY 0.723404 (-2600 4535);
PAINT GREEN (-2600 4535);
FORCEPROP 1 LAST $LOCATION H86
J 0
(-2600 4635);
DISPLAY 0.723404 (-2600 4635);
PAINT GREEN (-2600 4635);
FORCEPROP 0 LASTPIN (-2675 4425) $PN 1
J 2
(-2685 4435);
DISPLAY 0.680851 (-2685 4435);
PAINT MONO (-2685 4435);
FORCEPROP 1 LAST PATH I140
J 0
(-2425 4530);
DISPLAY 0.723404 (-2425 4530);
PAINT GREEN (-2425 4530);
DISPLAY INVISIBLE (-2425 4530);
FORCEPROP 1 LAST NEEDS_NO_SIZE TRUE
J 0
(-2475 4400);
DISPLAY 0.468085 (-2475 4400);
PAINT GREEN (-2475 4400);
DISPLAY INVISIBLE (-2475 4400);
FORCEPROP 2 LAST CDS_LIB pure_quanta
J 0
(-2475 4400);
DISPLAY INVISIBLE (-2475 4400);
FORCEPROP 0 LAST CDS_LOCATION H86
J 0
(-2625 4925);
DISPLAY 1.021277 (-2625 4925);
DISPLAY INVISIBLE (-2625 4925);
FORCEPROP 0 LAST $SEC 1
J 0
(-2625 4925);
DISPLAY 0.680851 (-2625 4925);
PAINT MONO (-2625 4925);
DISPLAY INVISIBLE (-2625 4925);
FORCEPROP 0 LAST CDS_SEC 1
J 0
(-2625 4925);
DISPLAY 1.021277 (-2625 4925);
DISPLAY INVISIBLE (-2625 4925);
FORCEADD UNIVERSAL_GND..1
(-2750 4025);
FORCEPROP 3 LASTPIN (-2750 4075) SIG_NAME GND\g
J 0
(-2740 4085);
DISPLAY 0.659574 (-2740 4085);
PAINT MONO (-2740 4085);
DISPLAY INVISIBLE (-2740 4085);
FORCEPROP 1 LAST HDL_POWER GND
J 1
(-2725 3950);
DISPLAY 0.872340 (-2725 3950);
PAINT GREEN (-2725 3950);
DISPLAY INVISIBLE (-2725 3950);
FORCEPROP 1 LAST PATH I141
J 0
(-2675 4025);
DISPLAY 0.872340 (-2675 4025);
PAINT AQUA (-2675 4025);
DISPLAY INVISIBLE (-2675 4025);
FORCEPROP 2 LAST CDS_LIB logical_power
J 0
(-2750 4025);
DISPLAY INVISIBLE (-2750 4025);
FORCEADD HOLE..1
(-1775 4400);
FORCEPROP 1 LAST PART_NUMBER HOLE596
J 0
(-1900 4580);
DISPLAY 0.723404 (-1900 4580);
PAINT GREEN (-1900 4580);
DISPLAY INVISIBLE (-1900 4580);
FORCEPROP 2 LAST PACK_TYPE TH
J 0
(-1925 4875);
DISPLAY 1.021277 (-1925 4875);
FORCEPROP 1 LAST MATERIAL EMPTY
J 0
(-1900 4535);
DISPLAY 0.723404 (-1900 4535);
PAINT GREEN (-1900 4535);
FORCEPROP 1 LAST $LOCATION H88
J 0
(-1900 4635);
DISPLAY 0.723404 (-1900 4635);
PAINT GREEN (-1900 4635);
FORCEPROP 0 LASTPIN (-1975 4425) $PN 1
J 2
(-1985 4435);
DISPLAY 0.680851 (-1985 4435);
PAINT MONO (-1985 4435);
FORCEPROP 1 LAST PATH I144
J 0
(-1725 4530);
DISPLAY 0.723404 (-1725 4530);
PAINT GREEN (-1725 4530);
DISPLAY INVISIBLE (-1725 4530);
FORCEPROP 1 LAST NEEDS_NO_SIZE TRUE
J 0
(-1775 4400);
DISPLAY 0.468085 (-1775 4400);
PAINT GREEN (-1775 4400);
DISPLAY INVISIBLE (-1775 4400);
FORCEPROP 2 LAST CDS_LIB pure_quanta
J 0
(-1775 4400);
DISPLAY INVISIBLE (-1775 4400);
FORCEPROP 0 LAST CDS_LOCATION H88
J 0
(-1925 4925);
DISPLAY 1.021277 (-1925 4925);
DISPLAY INVISIBLE (-1925 4925);
FORCEPROP 0 LAST $SEC 1
J 0
(-1925 4925);
DISPLAY 0.680851 (-1925 4925);
PAINT MONO (-1925 4925);
DISPLAY INVISIBLE (-1925 4925);
FORCEPROP 0 LAST CDS_SEC 1
J 0
(-1925 4925);
DISPLAY 1.021277 (-1925 4925);
DISPLAY INVISIBLE (-1925 4925);
FORCEADD UNIVERSAL_GND..1
(-2050 4025);
FORCEPROP 3 LASTPIN (-2050 4075) SIG_NAME GND\g
J 0
(-2040 4085);
DISPLAY 0.659574 (-2040 4085);
PAINT MONO (-2040 4085);
DISPLAY INVISIBLE (-2040 4085);
FORCEPROP 1 LAST HDL_POWER GND
J 1
(-2025 3950);
DISPLAY 0.872340 (-2025 3950);
PAINT GREEN (-2025 3950);
DISPLAY INVISIBLE (-2025 3950);
FORCEPROP 1 LAST PATH I145
J 0
(-1975 4025);
DISPLAY 0.872340 (-1975 4025);
PAINT AQUA (-1975 4025);
DISPLAY INVISIBLE (-1975 4025);
FORCEPROP 2 LAST CDS_LIB logical_power
J 0
(-2050 4025);
DISPLAY INVISIBLE (-2050 4025);
FORCEADD UNIVERSAL_GND..1
(-1375 4025);
FORCEPROP 3 LASTPIN (-1375 4075) SIG_NAME GND\g
J 0
(-1365 4085);
DISPLAY 0.659574 (-1365 4085);
PAINT MONO (-1365 4085);
DISPLAY INVISIBLE (-1365 4085);
FORCEPROP 1 LAST HDL_POWER GND
J 1
(-1350 3950);
DISPLAY 0.872340 (-1350 3950);
PAINT GREEN (-1350 3950);
DISPLAY INVISIBLE (-1350 3950);
FORCEPROP 1 LAST PATH I146
J 0
(-1300 4025);
DISPLAY 0.872340 (-1300 4025);
PAINT AQUA (-1300 4025);
DISPLAY INVISIBLE (-1300 4025);
FORCEPROP 2 LAST CDS_LIB logical_power
J 0
(-1375 4025);
DISPLAY INVISIBLE (-1375 4025);
FORCEADD HOLE..1
(-1100 4400);
FORCEPROP 1 LAST PART_NUMBER HOLE596
J 0
(-1225 4580);
DISPLAY 0.723404 (-1225 4580);
PAINT GREEN (-1225 4580);
DISPLAY INVISIBLE (-1225 4580);
FORCEPROP 2 LAST PACK_TYPE TH
J 0
(-1250 4875);
DISPLAY 1.021277 (-1250 4875);
FORCEPROP 1 LAST MATERIAL EMPTY
J 0
(-1225 4535);
DISPLAY 0.723404 (-1225 4535);
PAINT GREEN (-1225 4535);
FORCEPROP 1 LAST $LOCATION H91
J 0
(-1225 4635);
DISPLAY 0.723404 (-1225 4635);
PAINT GREEN (-1225 4635);
FORCEPROP 0 LASTPIN (-1300 4425) $PN 1
J 2
(-1310 4435);
DISPLAY 0.680851 (-1310 4435);
PAINT MONO (-1310 4435);
FORCEPROP 1 LAST PATH I147
J 0
(-1050 4530);
DISPLAY 0.723404 (-1050 4530);
PAINT GREEN (-1050 4530);
DISPLAY INVISIBLE (-1050 4530);
FORCEPROP 1 LAST NEEDS_NO_SIZE TRUE
J 0
(-1100 4400);
DISPLAY 0.468085 (-1100 4400);
PAINT GREEN (-1100 4400);
DISPLAY INVISIBLE (-1100 4400);
FORCEPROP 2 LAST CDS_LIB pure_quanta
J 0
(-1100 4400);
DISPLAY INVISIBLE (-1100 4400);
FORCEPROP 0 LAST CDS_LOCATION H91
J 0
(-1250 4925);
DISPLAY 1.021277 (-1250 4925);
DISPLAY INVISIBLE (-1250 4925);
FORCEPROP 0 LAST $SEC 1
J 0
(-1250 4925);
DISPLAY 0.680851 (-1250 4925);
PAINT MONO (-1250 4925);
DISPLAY INVISIBLE (-1250 4925);
FORCEPROP 0 LAST CDS_SEC 1
J 0
(-1250 4925);
DISPLAY 1.021277 (-1250 4925);
DISPLAY INVISIBLE (-1250 4925);
FORCEADD HOLE..1
(-425 4400);
FORCEPROP 1 LAST PART_NUMBER HOLE596
J 0
(-550 4580);
DISPLAY 0.723404 (-550 4580);
PAINT GREEN (-550 4580);
DISPLAY INVISIBLE (-550 4580);
FORCEPROP 2 LAST PACK_TYPE TH
J 0
(-575 4875);
DISPLAY 1.021277 (-575 4875);
FORCEPROP 1 LAST MATERIAL EMPTY
J 0
(-550 4535);
DISPLAY 0.723404 (-550 4535);
PAINT GREEN (-550 4535);
FORCEPROP 1 LAST $LOCATION H93
J 0
(-550 4635);
DISPLAY 0.723404 (-550 4635);
PAINT GREEN (-550 4635);
FORCEPROP 0 LASTPIN (-625 4425) $PN 1
J 2
(-635 4435);
DISPLAY 0.680851 (-635 4435);
PAINT MONO (-635 4435);
FORCEPROP 1 LAST PATH I148
J 0
(-375 4530);
DISPLAY 0.723404 (-375 4530);
PAINT GREEN (-375 4530);
DISPLAY INVISIBLE (-375 4530);
FORCEPROP 1 LAST NEEDS_NO_SIZE TRUE
J 0
(-425 4400);
DISPLAY 0.468085 (-425 4400);
PAINT GREEN (-425 4400);
DISPLAY INVISIBLE (-425 4400);
FORCEPROP 2 LAST CDS_LIB pure_quanta
J 0
(-425 4400);
DISPLAY INVISIBLE (-425 4400);
FORCEPROP 0 LAST CDS_LOCATION H93
J 0
(-575 4925);
DISPLAY 1.021277 (-575 4925);
DISPLAY INVISIBLE (-575 4925);
FORCEPROP 0 LAST $SEC 1
J 0
(-575 4925);
DISPLAY 0.680851 (-575 4925);
PAINT MONO (-575 4925);
DISPLAY INVISIBLE (-575 4925);
FORCEPROP 0 LAST CDS_SEC 1
J 0
(-575 4925);
DISPLAY 1.021277 (-575 4925);
DISPLAY INVISIBLE (-575 4925);
FORCEADD HOLE..1
(925 4400);
FORCEPROP 1 LAST PART_NUMBER HOLE596
J 0
(800 4580);
DISPLAY 0.723404 (800 4580);
PAINT GREEN (800 4580);
DISPLAY INVISIBLE (800 4580);
FORCEPROP 2 LAST PACK_TYPE TH
J 0
(775 4875);
DISPLAY 1.021277 (775 4875);
FORCEPROP 1 LAST MATERIAL EMPTY
J 0
(800 4535);
DISPLAY 0.723404 (800 4535);
PAINT GREEN (800 4535);
FORCEPROP 1 LAST $LOCATION H97
J 0
(800 4635);
DISPLAY 0.723404 (800 4635);
PAINT GREEN (800 4635);
FORCEPROP 0 LASTPIN (725 4425) $PN 1
J 2
(715 4435);
DISPLAY 0.680851 (715 4435);
PAINT MONO (715 4435);
FORCEPROP 1 LAST PATH I149
J 0
(975 4530);
DISPLAY 0.723404 (975 4530);
PAINT GREEN (975 4530);
DISPLAY INVISIBLE (975 4530);
FORCEPROP 1 LAST NEEDS_NO_SIZE TRUE
J 0
(925 4400);
DISPLAY 0.468085 (925 4400);
PAINT GREEN (925 4400);
DISPLAY INVISIBLE (925 4400);
FORCEPROP 2 LAST CDS_LIB pure_quanta
J 0
(925 4400);
DISPLAY INVISIBLE (925 4400);
FORCEPROP 0 LAST CDS_LOCATION H97
J 0
(775 4925);
DISPLAY 1.021277 (775 4925);
DISPLAY INVISIBLE (775 4925);
FORCEPROP 0 LAST $SEC 1
J 0
(775 4925);
DISPLAY 0.680851 (775 4925);
PAINT MONO (775 4925);
DISPLAY INVISIBLE (775 4925);
FORCEPROP 0 LAST CDS_SEC 1
J 0
(775 4925);
DISPLAY 1.021277 (775 4925);
DISPLAY INVISIBLE (775 4925);
FORCEADD HOLE..1
(250 4400);
FORCEPROP 1 LAST PART_NUMBER HOLE596
J 0
(125 4580);
DISPLAY 0.723404 (125 4580);
PAINT GREEN (125 4580);
DISPLAY INVISIBLE (125 4580);
FORCEPROP 2 LAST PACK_TYPE TH
J 0
(100 4875);
DISPLAY 1.021277 (100 4875);
FORCEPROP 1 LAST MATERIAL EMPTY
J 0
(125 4535);
DISPLAY 0.723404 (125 4535);
PAINT GREEN (125 4535);
FORCEPROP 1 LAST $LOCATION H95
J 0
(125 4635);
DISPLAY 0.723404 (125 4635);
PAINT GREEN (125 4635);
FORCEPROP 0 LASTPIN (50 4425) $PN 1
J 2
(40 4435);
DISPLAY 0.680851 (40 4435);
PAINT MONO (40 4435);
FORCEPROP 1 LAST PATH I150
J 0
(300 4530);
DISPLAY 0.723404 (300 4530);
PAINT GREEN (300 4530);
DISPLAY INVISIBLE (300 4530);
FORCEPROP 1 LAST NEEDS_NO_SIZE TRUE
J 0
(250 4400);
DISPLAY 0.468085 (250 4400);
PAINT GREEN (250 4400);
DISPLAY INVISIBLE (250 4400);
FORCEPROP 2 LAST CDS_LIB pure_quanta
J 0
(250 4400);
DISPLAY INVISIBLE (250 4400);
FORCEPROP 0 LAST CDS_LOCATION H95
J 0
(100 4925);
DISPLAY 1.021277 (100 4925);
DISPLAY INVISIBLE (100 4925);
FORCEPROP 0 LAST $SEC 1
J 0
(100 4925);
DISPLAY 0.680851 (100 4925);
PAINT MONO (100 4925);
DISPLAY INVISIBLE (100 4925);
FORCEPROP 0 LAST CDS_SEC 1
J 0
(100 4925);
DISPLAY 1.021277 (100 4925);
DISPLAY INVISIBLE (100 4925);
FORCEADD UNIVERSAL_GND..1
(650 4025);
FORCEPROP 3 LASTPIN (650 4075) SIG_NAME GND\g
J 0
(660 4085);
DISPLAY 0.659574 (660 4085);
PAINT MONO (660 4085);
DISPLAY INVISIBLE (660 4085);
FORCEPROP 1 LAST HDL_POWER GND
J 1
(675 3950);
DISPLAY 0.872340 (675 3950);
PAINT GREEN (675 3950);
DISPLAY INVISIBLE (675 3950);
FORCEPROP 1 LAST PATH I151
J 0
(725 4025);
DISPLAY 0.872340 (725 4025);
PAINT AQUA (725 4025);
DISPLAY INVISIBLE (725 4025);
FORCEPROP 2 LAST CDS_LIB logical_power
J 0
(650 4025);
DISPLAY INVISIBLE (650 4025);
FORCEADD UNIVERSAL_GND..1
(-25 4025);
FORCEPROP 3 LASTPIN (-25 4075) SIG_NAME GND\g
J 0
(-15 4085);
DISPLAY 0.659574 (-15 4085);
PAINT MONO (-15 4085);
DISPLAY INVISIBLE (-15 4085);
FORCEPROP 1 LAST HDL_POWER GND
J 1
(0 3950);
DISPLAY 0.872340 (0 3950);
PAINT GREEN (0 3950);
DISPLAY INVISIBLE (0 3950);
FORCEPROP 1 LAST PATH I152
J 0
(50 4025);
DISPLAY 0.872340 (50 4025);
PAINT AQUA (50 4025);
DISPLAY INVISIBLE (50 4025);
FORCEPROP 2 LAST CDS_LIB logical_power
J 0
(-25 4025);
DISPLAY INVISIBLE (-25 4025);
FORCEADD UNIVERSAL_GND..1
(-700 4025);
FORCEPROP 3 LASTPIN (-700 4075) SIG_NAME GND\g
J 0
(-690 4085);
DISPLAY 0.659574 (-690 4085);
PAINT MONO (-690 4085);
DISPLAY INVISIBLE (-690 4085);
FORCEPROP 1 LAST HDL_POWER GND
J 1
(-675 3950);
DISPLAY 0.872340 (-675 3950);
PAINT GREEN (-675 3950);
DISPLAY INVISIBLE (-675 3950);
FORCEPROP 1 LAST PATH I153
J 0
(-625 4025);
DISPLAY 0.872340 (-625 4025);
PAINT AQUA (-625 4025);
DISPLAY INVISIBLE (-625 4025);
FORCEPROP 2 LAST CDS_LIB logical_power
J 0
(-700 4025);
DISPLAY INVISIBLE (-700 4025);
FORCEADD HOLE..1
(2300 4425);
FORCEPROP 1 LAST PART_NUMBER HOLE596
J 0
(2175 4605);
DISPLAY 0.723404 (2175 4605);
PAINT GREEN (2175 4605);
DISPLAY INVISIBLE (2175 4605);
FORCEPROP 2 LAST PACK_TYPE TH
J 0
(2150 4900);
DISPLAY 1.021277 (2150 4900);
FORCEPROP 1 LAST MATERIAL EMPTY
J 0
(2175 4560);
DISPLAY 0.723404 (2175 4560);
PAINT GREEN (2175 4560);
FORCEPROP 1 LAST $LOCATION H101
J 0
(2175 4660);
DISPLAY 0.723404 (2175 4660);
PAINT GREEN (2175 4660);
FORCEPROP 0 LASTPIN (2100 4450) $PN 1
J 2
(2090 4460);
DISPLAY 0.680851 (2090 4460);
PAINT MONO (2090 4460);
FORCEPROP 1 LAST PATH I154
J 0
(2350 4555);
DISPLAY 0.723404 (2350 4555);
PAINT GREEN (2350 4555);
DISPLAY INVISIBLE (2350 4555);
FORCEPROP 1 LAST NEEDS_NO_SIZE TRUE
J 0
(2300 4425);
DISPLAY 0.468085 (2300 4425);
PAINT GREEN (2300 4425);
DISPLAY INVISIBLE (2300 4425);
FORCEPROP 2 LAST CDS_LIB pure_quanta
J 0
(2300 4425);
DISPLAY INVISIBLE (2300 4425);
FORCEPROP 0 LAST CDS_LOCATION H101
J 0
(2150 4950);
DISPLAY 1.021277 (2150 4950);
DISPLAY INVISIBLE (2150 4950);
FORCEPROP 0 LAST $SEC 1
J 0
(2150 4950);
DISPLAY 0.680851 (2150 4950);
PAINT MONO (2150 4950);
DISPLAY INVISIBLE (2150 4950);
FORCEPROP 0 LAST CDS_SEC 1
J 0
(2150 4950);
DISPLAY 1.021277 (2150 4950);
DISPLAY INVISIBLE (2150 4950);
FORCEADD HOLE..1
(1625 4425);
FORCEPROP 1 LAST PART_NUMBER HOLE596
J 0
(1500 4605);
DISPLAY 0.723404 (1500 4605);
PAINT GREEN (1500 4605);
DISPLAY INVISIBLE (1500 4605);
FORCEPROP 2 LAST PACK_TYPE TH
J 0
(1475 4900);
DISPLAY 1.021277 (1475 4900);
FORCEPROP 1 LAST MATERIAL EMPTY
J 0
(1500 4560);
DISPLAY 0.723404 (1500 4560);
PAINT GREEN (1500 4560);
FORCEPROP 1 LAST $LOCATION H99
J 0
(1500 4660);
DISPLAY 0.723404 (1500 4660);
PAINT GREEN (1500 4660);
FORCEPROP 0 LASTPIN (1425 4450) $PN 1
J 2
(1415 4460);
DISPLAY 0.680851 (1415 4460);
PAINT MONO (1415 4460);
FORCEPROP 1 LAST PATH I155
J 0
(1675 4555);
DISPLAY 0.723404 (1675 4555);
PAINT GREEN (1675 4555);
DISPLAY INVISIBLE (1675 4555);
FORCEPROP 1 LAST NEEDS_NO_SIZE TRUE
J 0
(1625 4425);
DISPLAY 0.468085 (1625 4425);
PAINT GREEN (1625 4425);
DISPLAY INVISIBLE (1625 4425);
FORCEPROP 2 LAST CDS_LIB pure_quanta
J 0
(1625 4425);
DISPLAY INVISIBLE (1625 4425);
FORCEPROP 0 LAST CDS_LOCATION H99
J 0
(1475 4950);
DISPLAY 1.021277 (1475 4950);
DISPLAY INVISIBLE (1475 4950);
FORCEPROP 0 LAST $SEC 1
J 0
(1475 4950);
DISPLAY 0.680851 (1475 4950);
PAINT MONO (1475 4950);
DISPLAY INVISIBLE (1475 4950);
FORCEPROP 0 LAST CDS_SEC 1
J 0
(1475 4950);
DISPLAY 1.021277 (1475 4950);
DISPLAY INVISIBLE (1475 4950);
FORCEADD UNIVERSAL_GND..1
(2025 4050);
FORCEPROP 3 LASTPIN (2025 4100) SIG_NAME GND\g
J 0
(2035 4110);
DISPLAY 0.659574 (2035 4110);
PAINT MONO (2035 4110);
DISPLAY INVISIBLE (2035 4110);
FORCEPROP 1 LAST HDL_POWER GND
J 1
(2050 3975);
DISPLAY 0.872340 (2050 3975);
PAINT GREEN (2050 3975);
DISPLAY INVISIBLE (2050 3975);
FORCEPROP 1 LAST PATH I156
J 0
(2100 4050);
DISPLAY 0.872340 (2100 4050);
PAINT AQUA (2100 4050);
DISPLAY INVISIBLE (2100 4050);
FORCEPROP 2 LAST CDS_LIB logical_power
J 0
(2025 4050);
DISPLAY INVISIBLE (2025 4050);
FORCEADD UNIVERSAL_GND..1
(1350 4050);
FORCEPROP 3 LASTPIN (1350 4100) SIG_NAME GND\g
J 0
(1360 4110);
DISPLAY 0.659574 (1360 4110);
PAINT MONO (1360 4110);
DISPLAY INVISIBLE (1360 4110);
FORCEPROP 1 LAST HDL_POWER GND
J 1
(1375 3975);
DISPLAY 0.872340 (1375 3975);
PAINT GREEN (1375 3975);
DISPLAY INVISIBLE (1375 3975);
FORCEPROP 1 LAST PATH I157
J 0
(1425 4050);
DISPLAY 0.872340 (1425 4050);
PAINT AQUA (1425 4050);
DISPLAY INVISIBLE (1425 4050);
FORCEPROP 2 LAST CDS_LIB logical_power
J 0
(1350 4050);
DISPLAY INVISIBLE (1350 4050);
FORCEADD HOLE..1
(2300 3550);
FORCEPROP 1 LAST PART_NUMBER HOLE596
J 0
(2175 3730);
DISPLAY 0.723404 (2175 3730);
PAINT GREEN (2175 3730);
DISPLAY INVISIBLE (2175 3730);
FORCEPROP 2 LAST PACK_TYPE TH
J 0
(2150 4025);
DISPLAY 1.021277 (2150 4025);
FORCEPROP 1 LAST MATERIAL EMPTY
J 0
(2175 3685);
DISPLAY 0.723404 (2175 3685);
PAINT GREEN (2175 3685);
FORCEPROP 1 LAST $LOCATION H102
J 0
(2175 3785);
DISPLAY 0.723404 (2175 3785);
PAINT GREEN (2175 3785);
FORCEPROP 0 LASTPIN (2100 3575) $PN 1
J 2
(2090 3585);
DISPLAY 0.680851 (2090 3585);
PAINT MONO (2090 3585);
FORCEPROP 1 LAST PATH I158
J 0
(2350 3680);
DISPLAY 0.723404 (2350 3680);
PAINT GREEN (2350 3680);
DISPLAY INVISIBLE (2350 3680);
FORCEPROP 1 LAST NEEDS_NO_SIZE TRUE
J 0
(2300 3550);
DISPLAY 0.468085 (2300 3550);
PAINT GREEN (2300 3550);
DISPLAY INVISIBLE (2300 3550);
FORCEPROP 2 LAST CDS_LIB pure_quanta
J 0
(2300 3550);
DISPLAY INVISIBLE (2300 3550);
FORCEPROP 0 LAST CDS_LOCATION H102
J 0
(2150 4075);
DISPLAY 1.021277 (2150 4075);
DISPLAY INVISIBLE (2150 4075);
FORCEPROP 0 LAST $SEC 1
J 0
(2150 4075);
DISPLAY 0.680851 (2150 4075);
PAINT MONO (2150 4075);
DISPLAY INVISIBLE (2150 4075);
FORCEPROP 0 LAST CDS_SEC 1
J 0
(2150 4075);
DISPLAY 1.021277 (2150 4075);
DISPLAY INVISIBLE (2150 4075);
FORCEADD HOLE..1
(1625 3550);
FORCEPROP 1 LAST PART_NUMBER HOLE596
J 0
(1500 3730);
DISPLAY 0.723404 (1500 3730);
PAINT GREEN (1500 3730);
DISPLAY INVISIBLE (1500 3730);
FORCEPROP 1 LAST MATERIAL EMPTY
J 0
(1500 3685);
DISPLAY 0.723404 (1500 3685);
PAINT GREEN (1500 3685);
FORCEPROP 2 LAST PACK_TYPE TH
J 0
(1475 4025);
DISPLAY 1.021277 (1475 4025);
FORCEPROP 1 LAST $LOCATION H100
J 0
(1500 3785);
DISPLAY 0.723404 (1500 3785);
PAINT GREEN (1500 3785);
FORCEPROP 0 LASTPIN (1425 3575) $PN 1
J 2
(1415 3585);
DISPLAY 0.680851 (1415 3585);
PAINT MONO (1415 3585);
FORCEPROP 2 LAST CDS_LIB pure_quanta
J 0
(1625 3550);
DISPLAY INVISIBLE (1625 3550);
FORCEPROP 1 LAST NEEDS_NO_SIZE TRUE
J 0
(1625 3550);
DISPLAY 0.468085 (1625 3550);
PAINT GREEN (1625 3550);
DISPLAY INVISIBLE (1625 3550);
FORCEPROP 1 LAST PATH I159
J 0
(1675 3680);
DISPLAY 0.723404 (1675 3680);
PAINT GREEN (1675 3680);
DISPLAY INVISIBLE (1675 3680);
FORCEPROP 0 LAST CDS_LOCATION H100
J 0
(1475 4075);
DISPLAY 1.021277 (1475 4075);
DISPLAY INVISIBLE (1475 4075);
FORCEPROP 0 LAST $SEC 1
J 0
(1475 4075);
DISPLAY 0.680851 (1475 4075);
PAINT MONO (1475 4075);
DISPLAY INVISIBLE (1475 4075);
FORCEPROP 0 LAST CDS_SEC 1
J 0
(1475 4075);
DISPLAY 1.021277 (1475 4075);
DISPLAY INVISIBLE (1475 4075);
FORCEADD HOLE..1
(925 3525);
FORCEPROP 1 LAST PART_NUMBER HOLE596
J 0
(800 3705);
DISPLAY 0.723404 (800 3705);
PAINT GREEN (800 3705);
DISPLAY INVISIBLE (800 3705);
FORCEPROP 2 LAST PACK_TYPE TH
J 0
(775 4000);
DISPLAY 1.021277 (775 4000);
FORCEPROP 1 LAST MATERIAL EMPTY
J 0
(800 3660);
DISPLAY 0.723404 (800 3660);
PAINT GREEN (800 3660);
FORCEPROP 1 LAST $LOCATION H98
J 0
(800 3760);
DISPLAY 0.723404 (800 3760);
PAINT GREEN (800 3760);
FORCEPROP 0 LASTPIN (725 3550) $PN 1
J 2
(715 3560);
DISPLAY 0.680851 (715 3560);
PAINT MONO (715 3560);
FORCEPROP 1 LAST PATH I160
J 0
(975 3655);
DISPLAY 0.723404 (975 3655);
PAINT GREEN (975 3655);
DISPLAY INVISIBLE (975 3655);
FORCEPROP 1 LAST NEEDS_NO_SIZE TRUE
J 0
(925 3525);
DISPLAY 0.468085 (925 3525);
PAINT GREEN (925 3525);
DISPLAY INVISIBLE (925 3525);
FORCEPROP 2 LAST CDS_LIB pure_quanta
J 0
(925 3525);
DISPLAY INVISIBLE (925 3525);
FORCEPROP 0 LAST CDS_LOCATION H98
J 0
(775 4050);
DISPLAY 1.021277 (775 4050);
DISPLAY INVISIBLE (775 4050);
FORCEPROP 0 LAST $SEC 1
J 0
(775 4050);
DISPLAY 0.680851 (775 4050);
PAINT MONO (775 4050);
DISPLAY INVISIBLE (775 4050);
FORCEPROP 0 LAST CDS_SEC 1
J 0
(775 4050);
DISPLAY 1.021277 (775 4050);
DISPLAY INVISIBLE (775 4050);
FORCEADD HOLE..1
(250 3525);
FORCEPROP 1 LAST PART_NUMBER HOLE596
J 0
(125 3705);
DISPLAY 0.723404 (125 3705);
PAINT GREEN (125 3705);
DISPLAY INVISIBLE (125 3705);
FORCEPROP 2 LAST PACK_TYPE TH
J 0
(100 4000);
DISPLAY 1.021277 (100 4000);
FORCEPROP 1 LAST MATERIAL EMPTY
J 0
(125 3660);
DISPLAY 0.723404 (125 3660);
PAINT GREEN (125 3660);
FORCEPROP 1 LAST $LOCATION H96
J 0
(125 3760);
DISPLAY 0.723404 (125 3760);
PAINT GREEN (125 3760);
FORCEPROP 0 LASTPIN (50 3550) $PN 1
J 2
(40 3560);
DISPLAY 0.680851 (40 3560);
PAINT MONO (40 3560);
FORCEPROP 1 LAST PATH I161
J 0
(300 3655);
DISPLAY 0.723404 (300 3655);
PAINT GREEN (300 3655);
DISPLAY INVISIBLE (300 3655);
FORCEPROP 1 LAST NEEDS_NO_SIZE TRUE
J 0
(250 3525);
DISPLAY 0.468085 (250 3525);
PAINT GREEN (250 3525);
DISPLAY INVISIBLE (250 3525);
FORCEPROP 2 LAST CDS_LIB pure_quanta
J 0
(250 3525);
DISPLAY INVISIBLE (250 3525);
FORCEPROP 0 LAST CDS_LOCATION H96
J 0
(100 4050);
DISPLAY 1.021277 (100 4050);
DISPLAY INVISIBLE (100 4050);
FORCEPROP 0 LAST $SEC 1
J 0
(100 4050);
DISPLAY 0.680851 (100 4050);
PAINT MONO (100 4050);
DISPLAY INVISIBLE (100 4050);
FORCEPROP 0 LAST CDS_SEC 1
J 0
(100 4050);
DISPLAY 1.021277 (100 4050);
DISPLAY INVISIBLE (100 4050);
FORCEADD UNIVERSAL_GND..1
(1350 3175);
FORCEPROP 3 LASTPIN (1350 3225) SIG_NAME GND\g
J 0
(1360 3235);
DISPLAY 0.659574 (1360 3235);
PAINT MONO (1360 3235);
DISPLAY INVISIBLE (1360 3235);
FORCEPROP 2 LAST CDS_LIB logical_power
J 0
(1350 3175);
DISPLAY INVISIBLE (1350 3175);
FORCEPROP 1 LAST PATH I162
J 0
(1425 3175);
DISPLAY 0.872340 (1425 3175);
PAINT AQUA (1425 3175);
DISPLAY INVISIBLE (1425 3175);
FORCEPROP 1 LAST HDL_POWER GND
J 1
(1375 3100);
DISPLAY 0.872340 (1375 3100);
PAINT GREEN (1375 3100);
DISPLAY INVISIBLE (1375 3100);
FORCEADD UNIVERSAL_GND..1
(2025 3175);
FORCEPROP 3 LASTPIN (2025 3225) SIG_NAME GND\g
J 0
(2035 3235);
DISPLAY 0.659574 (2035 3235);
PAINT MONO (2035 3235);
DISPLAY INVISIBLE (2035 3235);
FORCEPROP 1 LAST HDL_POWER GND
J 1
(2050 3100);
DISPLAY 0.872340 (2050 3100);
PAINT GREEN (2050 3100);
DISPLAY INVISIBLE (2050 3100);
FORCEPROP 1 LAST PATH I163
J 0
(2100 3175);
DISPLAY 0.872340 (2100 3175);
PAINT AQUA (2100 3175);
DISPLAY INVISIBLE (2100 3175);
FORCEPROP 2 LAST CDS_LIB logical_power
J 0
(2025 3175);
DISPLAY INVISIBLE (2025 3175);
FORCEADD UNIVERSAL_GND..1
(650 3075);
FORCEPROP 3 LASTPIN (650 3125) SIG_NAME GND\g
J 0
(660 3135);
DISPLAY 0.659574 (660 3135);
PAINT MONO (660 3135);
DISPLAY INVISIBLE (660 3135);
FORCEPROP 2 LAST CDS_LIB logical_power
J 0
(650 3075);
DISPLAY INVISIBLE (650 3075);
FORCEPROP 1 LAST PATH I164
J 0
(725 3075);
DISPLAY 0.872340 (725 3075);
PAINT AQUA (725 3075);
DISPLAY INVISIBLE (725 3075);
FORCEPROP 1 LAST HDL_POWER GND
J 1
(675 3000);
DISPLAY 0.872340 (675 3000);
PAINT GREEN (675 3000);
DISPLAY INVISIBLE (675 3000);
FORCEADD HOLE..1
(-425 3525);
FORCEPROP 1 LAST PART_NUMBER HOLE596
J 0
(-550 3705);
DISPLAY 0.723404 (-550 3705);
PAINT GREEN (-550 3705);
DISPLAY INVISIBLE (-550 3705);
FORCEPROP 1 LAST MATERIAL EMPTY
J 0
(-550 3660);
DISPLAY 0.723404 (-550 3660);
PAINT GREEN (-550 3660);
FORCEPROP 2 LAST PACK_TYPE TH
J 0
(-575 4000);
DISPLAY 1.021277 (-575 4000);
FORCEPROP 1 LAST $LOCATION H94
J 0
(-550 3760);
DISPLAY 0.723404 (-550 3760);
PAINT GREEN (-550 3760);
FORCEPROP 0 LASTPIN (-625 3550) $PN 1
J 2
(-635 3560);
DISPLAY 0.680851 (-635 3560);
PAINT MONO (-635 3560);
FORCEPROP 1 LAST PATH I165
J 0
(-375 3655);
DISPLAY 0.723404 (-375 3655);
PAINT GREEN (-375 3655);
DISPLAY INVISIBLE (-375 3655);
FORCEPROP 1 LAST NEEDS_NO_SIZE TRUE
J 0
(-425 3525);
DISPLAY 0.468085 (-425 3525);
PAINT GREEN (-425 3525);
DISPLAY INVISIBLE (-425 3525);
FORCEPROP 2 LAST CDS_LIB pure_quanta
J 0
(-425 3525);
DISPLAY INVISIBLE (-425 3525);
FORCEPROP 0 LAST CDS_LOCATION H94
J 0
(-575 4050);
DISPLAY 1.021277 (-575 4050);
DISPLAY INVISIBLE (-575 4050);
FORCEPROP 0 LAST $SEC 1
J 0
(-575 4050);
DISPLAY 0.680851 (-575 4050);
PAINT MONO (-575 4050);
DISPLAY INVISIBLE (-575 4050);
FORCEPROP 0 LAST CDS_SEC 1
J 0
(-575 4050);
DISPLAY 1.021277 (-575 4050);
DISPLAY INVISIBLE (-575 4050);
FORCEADD HOLE..1
(-1100 3525);
FORCEPROP 1 LAST PART_NUMBER HOLE596
J 0
(-1225 3705);
DISPLAY 0.723404 (-1225 3705);
PAINT GREEN (-1225 3705);
DISPLAY INVISIBLE (-1225 3705);
FORCEPROP 1 LAST MATERIAL EMPTY
J 0
(-1225 3660);
DISPLAY 0.723404 (-1225 3660);
PAINT GREEN (-1225 3660);
FORCEPROP 2 LAST PACK_TYPE TH
J 0
(-1250 4000);
DISPLAY 1.021277 (-1250 4000);
FORCEPROP 1 LAST $LOCATION H92
J 0
(-1225 3760);
DISPLAY 0.723404 (-1225 3760);
PAINT GREEN (-1225 3760);
FORCEPROP 0 LASTPIN (-1300 3550) $PN 1
J 2
(-1310 3560);
DISPLAY 0.680851 (-1310 3560);
PAINT MONO (-1310 3560);
FORCEPROP 1 LAST PATH I166
J 0
(-1050 3655);
DISPLAY 0.723404 (-1050 3655);
PAINT GREEN (-1050 3655);
DISPLAY INVISIBLE (-1050 3655);
FORCEPROP 1 LAST NEEDS_NO_SIZE TRUE
J 0
(-1100 3525);
DISPLAY 0.468085 (-1100 3525);
PAINT GREEN (-1100 3525);
DISPLAY INVISIBLE (-1100 3525);
FORCEPROP 2 LAST CDS_LIB pure_quanta
J 0
(-1100 3525);
DISPLAY INVISIBLE (-1100 3525);
FORCEPROP 0 LAST CDS_LOCATION H92
J 0
(-1250 4050);
DISPLAY 1.021277 (-1250 4050);
DISPLAY INVISIBLE (-1250 4050);
FORCEPROP 0 LAST $SEC 1
J 0
(-1250 4050);
DISPLAY 0.680851 (-1250 4050);
PAINT MONO (-1250 4050);
DISPLAY INVISIBLE (-1250 4050);
FORCEPROP 0 LAST CDS_SEC 1
J 0
(-1250 4050);
DISPLAY 1.021277 (-1250 4050);
DISPLAY INVISIBLE (-1250 4050);
FORCEADD HOLE..1
(-1775 3525);
FORCEPROP 1 LAST PART_NUMBER HOLE596
J 0
(-1900 3705);
DISPLAY 0.723404 (-1900 3705);
PAINT GREEN (-1900 3705);
DISPLAY INVISIBLE (-1900 3705);
FORCEPROP 2 LAST PACK_TYPE TH
J 0
(-1925 4000);
DISPLAY 1.021277 (-1925 4000);
FORCEPROP 1 LAST MATERIAL EMPTY
J 0
(-1900 3660);
DISPLAY 0.723404 (-1900 3660);
PAINT GREEN (-1900 3660);
FORCEPROP 1 LAST $LOCATION H89
J 0
(-1900 3760);
DISPLAY 0.723404 (-1900 3760);
PAINT GREEN (-1900 3760);
FORCEPROP 0 LASTPIN (-1975 3550) $PN 1
J 2
(-1985 3560);
DISPLAY 0.680851 (-1985 3560);
PAINT MONO (-1985 3560);
FORCEPROP 1 LAST PATH I167
J 0
(-1725 3655);
DISPLAY 0.723404 (-1725 3655);
PAINT GREEN (-1725 3655);
DISPLAY INVISIBLE (-1725 3655);
FORCEPROP 1 LAST NEEDS_NO_SIZE TRUE
J 0
(-1775 3525);
DISPLAY 0.468085 (-1775 3525);
PAINT GREEN (-1775 3525);
DISPLAY INVISIBLE (-1775 3525);
FORCEPROP 2 LAST CDS_LIB pure_quanta
J 0
(-1775 3525);
DISPLAY INVISIBLE (-1775 3525);
FORCEPROP 0 LAST CDS_LOCATION H89
J 0
(-1925 4050);
DISPLAY 1.021277 (-1925 4050);
DISPLAY INVISIBLE (-1925 4050);
FORCEPROP 0 LAST $SEC 1
J 0
(-1925 4050);
DISPLAY 0.680851 (-1925 4050);
PAINT MONO (-1925 4050);
DISPLAY INVISIBLE (-1925 4050);
FORCEPROP 0 LAST CDS_SEC 1
J 0
(-1925 4050);
DISPLAY 1.021277 (-1925 4050);
DISPLAY INVISIBLE (-1925 4050);
FORCEADD HOLE..1
(-2475 3525);
FORCEPROP 1 LAST PART_NUMBER HOLE596
J 0
(-2600 3705);
DISPLAY 0.723404 (-2600 3705);
PAINT GREEN (-2600 3705);
DISPLAY INVISIBLE (-2600 3705);
FORCEPROP 1 LAST MATERIAL EMPTY
J 0
(-2600 3660);
DISPLAY 0.723404 (-2600 3660);
PAINT GREEN (-2600 3660);
FORCEPROP 2 LAST PACK_TYPE TH
J 0
(-2625 4000);
DISPLAY 1.021277 (-2625 4000);
FORCEPROP 1 LAST $LOCATION H87
J 0
(-2600 3760);
DISPLAY 0.723404 (-2600 3760);
PAINT GREEN (-2600 3760);
FORCEPROP 0 LASTPIN (-2675 3550) $PN 1
J 2
(-2685 3560);
DISPLAY 0.680851 (-2685 3560);
PAINT MONO (-2685 3560);
FORCEPROP 1 LAST PATH I168
J 0
(-2425 3655);
DISPLAY 0.723404 (-2425 3655);
PAINT GREEN (-2425 3655);
DISPLAY INVISIBLE (-2425 3655);
FORCEPROP 1 LAST NEEDS_NO_SIZE TRUE
J 0
(-2475 3525);
DISPLAY 0.468085 (-2475 3525);
PAINT GREEN (-2475 3525);
DISPLAY INVISIBLE (-2475 3525);
FORCEPROP 2 LAST CDS_LIB pure_quanta
J 0
(-2475 3525);
DISPLAY INVISIBLE (-2475 3525);
FORCEPROP 0 LAST CDS_LOCATION H87
J 0
(-2625 4050);
DISPLAY 1.021277 (-2625 4050);
DISPLAY INVISIBLE (-2625 4050);
FORCEPROP 0 LAST $SEC 1
J 0
(-2625 4050);
DISPLAY 0.680851 (-2625 4050);
PAINT MONO (-2625 4050);
DISPLAY INVISIBLE (-2625 4050);
FORCEPROP 0 LAST CDS_SEC 1
J 0
(-2625 4050);
DISPLAY 1.021277 (-2625 4050);
DISPLAY INVISIBLE (-2625 4050);
FORCEADD UNIVERSAL_GND..1
(-25 3075);
FORCEPROP 3 LASTPIN (-25 3125) SIG_NAME GND\g
J 0
(-15 3135);
DISPLAY 0.659574 (-15 3135);
PAINT MONO (-15 3135);
DISPLAY INVISIBLE (-15 3135);
FORCEPROP 2 LAST CDS_LIB logical_power
J 0
(-25 3075);
DISPLAY INVISIBLE (-25 3075);
FORCEPROP 1 LAST PATH I169
J 0
(50 3075);
DISPLAY 0.872340 (50 3075);
PAINT AQUA (50 3075);
DISPLAY INVISIBLE (50 3075);
FORCEPROP 1 LAST HDL_POWER GND
J 1
(0 3000);
DISPLAY 0.872340 (0 3000);
PAINT GREEN (0 3000);
DISPLAY INVISIBLE (0 3000);
FORCEADD UNIVERSAL_GND..1
(-700 3075);
FORCEPROP 3 LASTPIN (-700 3125) SIG_NAME GND\g
J 0
(-690 3135);
DISPLAY 0.659574 (-690 3135);
PAINT MONO (-690 3135);
DISPLAY INVISIBLE (-690 3135);
FORCEPROP 2 LAST CDS_LIB logical_power
J 0
(-700 3075);
DISPLAY INVISIBLE (-700 3075);
FORCEPROP 1 LAST PATH I170
J 0
(-625 3075);
DISPLAY 0.872340 (-625 3075);
PAINT AQUA (-625 3075);
DISPLAY INVISIBLE (-625 3075);
FORCEPROP 1 LAST HDL_POWER GND
J 1
(-675 3000);
DISPLAY 0.872340 (-675 3000);
PAINT GREEN (-675 3000);
DISPLAY INVISIBLE (-675 3000);
FORCEADD UNIVERSAL_GND..1
(-1375 3075);
FORCEPROP 3 LASTPIN (-1375 3125) SIG_NAME GND\g
J 0
(-1365 3135);
DISPLAY 0.659574 (-1365 3135);
PAINT MONO (-1365 3135);
DISPLAY INVISIBLE (-1365 3135);
FORCEPROP 2 LAST CDS_LIB logical_power
J 0
(-1375 3075);
DISPLAY INVISIBLE (-1375 3075);
FORCEPROP 1 LAST PATH I171
J 0
(-1300 3075);
DISPLAY 0.872340 (-1300 3075);
PAINT AQUA (-1300 3075);
DISPLAY INVISIBLE (-1300 3075);
FORCEPROP 1 LAST HDL_POWER GND
J 1
(-1350 3000);
DISPLAY 0.872340 (-1350 3000);
PAINT GREEN (-1350 3000);
DISPLAY INVISIBLE (-1350 3000);
FORCEADD UNIVERSAL_GND..1
(-2050 3075);
FORCEPROP 3 LASTPIN (-2050 3125) SIG_NAME GND\g
J 0
(-2040 3135);
DISPLAY 0.659574 (-2040 3135);
PAINT MONO (-2040 3135);
DISPLAY INVISIBLE (-2040 3135);
FORCEPROP 2 LAST CDS_LIB logical_power
J 0
(-2050 3075);
DISPLAY INVISIBLE (-2050 3075);
FORCEPROP 1 LAST PATH I172
J 0
(-1975 3075);
DISPLAY 0.872340 (-1975 3075);
PAINT AQUA (-1975 3075);
DISPLAY INVISIBLE (-1975 3075);
FORCEPROP 1 LAST HDL_POWER GND
J 1
(-2025 3000);
DISPLAY 0.872340 (-2025 3000);
PAINT GREEN (-2025 3000);
DISPLAY INVISIBLE (-2025 3000);
FORCEADD UNIVERSAL_GND..1
(-2750 3150);
FORCEPROP 3 LASTPIN (-2750 3200) SIG_NAME GND\g
J 0
(-2740 3210);
DISPLAY 0.659574 (-2740 3210);
PAINT MONO (-2740 3210);
DISPLAY INVISIBLE (-2740 3210);
FORCEPROP 1 LAST HDL_POWER GND
J 1
(-2725 3075);
DISPLAY 0.872340 (-2725 3075);
PAINT GREEN (-2725 3075);
DISPLAY INVISIBLE (-2725 3075);
FORCEPROP 1 LAST PATH I173
J 0
(-2675 3150);
DISPLAY 0.872340 (-2675 3150);
PAINT AQUA (-2675 3150);
DISPLAY INVISIBLE (-2675 3150);
FORCEPROP 2 LAST CDS_LIB logical_power
J 0
(-2750 3150);
DISPLAY INVISIBLE (-2750 3150);
FORCEADD HOLE..1
(3025 4425);
FORCEPROP 1 LAST PART_NUMBER HOLE596
J 0
(2900 4605);
DISPLAY 0.723404 (2900 4605);
PAINT GREEN (2900 4605);
DISPLAY INVISIBLE (2900 4605);
FORCEPROP 2 LAST PACK_TYPE TH
J 0
(2875 4900);
DISPLAY 1.021277 (2875 4900);
FORCEPROP 1 LAST MATERIAL EMPTY
J 0
(2900 4560);
DISPLAY 0.723404 (2900 4560);
PAINT GREEN (2900 4560);
FORCEPROP 1 LAST $LOCATION H103
J 0
(2900 4660);
DISPLAY 0.723404 (2900 4660);
PAINT GREEN (2900 4660);
FORCEPROP 0 LASTPIN (2825 4450) $PN 1
J 2
(2815 4460);
DISPLAY 0.680851 (2815 4460);
PAINT MONO (2815 4460);
FORCEPROP 1 LAST PATH I174
J 0
(3075 4555);
DISPLAY 0.723404 (3075 4555);
PAINT GREEN (3075 4555);
DISPLAY INVISIBLE (3075 4555);
FORCEPROP 1 LAST NEEDS_NO_SIZE TRUE
J 0
(3025 4425);
DISPLAY 0.468085 (3025 4425);
PAINT GREEN (3025 4425);
DISPLAY INVISIBLE (3025 4425);
FORCEPROP 2 LAST CDS_LIB pure_quanta
J 0
(3025 4425);
DISPLAY INVISIBLE (3025 4425);
FORCEPROP 0 LAST CDS_LOCATION H103
J 0
(2875 4950);
DISPLAY 1.021277 (2875 4950);
DISPLAY INVISIBLE (2875 4950);
FORCEPROP 0 LAST $SEC 1
J 0
(2875 4950);
DISPLAY 0.680851 (2875 4950);
PAINT MONO (2875 4950);
DISPLAY INVISIBLE (2875 4950);
FORCEPROP 0 LAST CDS_SEC 1
J 0
(2875 4950);
DISPLAY 1.021277 (2875 4950);
DISPLAY INVISIBLE (2875 4950);
FORCEADD HOLE..1
(3025 3550);
FORCEPROP 1 LAST PART_NUMBER HOLE596
J 0
(2900 3730);
DISPLAY 0.723404 (2900 3730);
PAINT GREEN (2900 3730);
DISPLAY INVISIBLE (2900 3730);
FORCEPROP 2 LAST PACK_TYPE TH
J 0
(2875 4025);
DISPLAY 1.021277 (2875 4025);
FORCEPROP 1 LAST MATERIAL EMPTY
J 0
(2900 3685);
DISPLAY 0.723404 (2900 3685);
PAINT GREEN (2900 3685);
FORCEPROP 1 LAST $LOCATION H104
J 0
(2900 3785);
DISPLAY 0.723404 (2900 3785);
PAINT GREEN (2900 3785);
FORCEPROP 0 LASTPIN (2825 3575) $PN 1
J 2
(2815 3585);
DISPLAY 0.680851 (2815 3585);
PAINT MONO (2815 3585);
FORCEPROP 1 LAST PATH I175
J 0
(3075 3680);
DISPLAY 0.723404 (3075 3680);
PAINT GREEN (3075 3680);
DISPLAY INVISIBLE (3075 3680);
FORCEPROP 1 LAST NEEDS_NO_SIZE TRUE
J 0
(3025 3550);
DISPLAY 0.468085 (3025 3550);
PAINT GREEN (3025 3550);
DISPLAY INVISIBLE (3025 3550);
FORCEPROP 2 LAST CDS_LIB pure_quanta
J 0
(3025 3550);
DISPLAY INVISIBLE (3025 3550);
FORCEPROP 0 LAST CDS_LOCATION H104
J 0
(2875 4075);
DISPLAY 1.021277 (2875 4075);
DISPLAY INVISIBLE (2875 4075);
FORCEPROP 0 LAST $SEC 1
J 0
(2875 4075);
DISPLAY 0.680851 (2875 4075);
PAINT MONO (2875 4075);
DISPLAY INVISIBLE (2875 4075);
FORCEPROP 0 LAST CDS_SEC 1
J 0
(2875 4075);
DISPLAY 1.021277 (2875 4075);
DISPLAY INVISIBLE (2875 4075);
FORCEADD UNIVERSAL_GND..1
(2750 4050);
FORCEPROP 3 LASTPIN (2750 4100) SIG_NAME GND\g
J 0
(2760 4110);
DISPLAY 0.659574 (2760 4110);
PAINT MONO (2760 4110);
DISPLAY INVISIBLE (2760 4110);
FORCEPROP 1 LAST HDL_POWER GND
J 1
(2775 3975);
DISPLAY 0.872340 (2775 3975);
PAINT GREEN (2775 3975);
DISPLAY INVISIBLE (2775 3975);
FORCEPROP 1 LAST PATH I176
J 0
(2825 4050);
DISPLAY 0.872340 (2825 4050);
PAINT AQUA (2825 4050);
DISPLAY INVISIBLE (2825 4050);
FORCEPROP 2 LAST CDS_LIB logical_power
J 0
(2750 4050);
DISPLAY INVISIBLE (2750 4050);
FORCEADD UNIVERSAL_GND..1
(2750 3175);
FORCEPROP 3 LASTPIN (2750 3225) SIG_NAME GND\g
J 0
(2760 3235);
DISPLAY 0.659574 (2760 3235);
PAINT MONO (2760 3235);
DISPLAY INVISIBLE (2760 3235);
FORCEPROP 1 LAST HDL_POWER GND
J 1
(2775 3100);
DISPLAY 0.872340 (2775 3100);
PAINT GREEN (2775 3100);
DISPLAY INVISIBLE (2775 3100);
FORCEPROP 1 LAST PATH I177
J 0
(2825 3175);
DISPLAY 0.872340 (2825 3175);
PAINT AQUA (2825 3175);
DISPLAY INVISIBLE (2825 3175);
FORCEPROP 2 LAST CDS_LIB logical_power
J 0
(2750 3175);
DISPLAY INVISIBLE (2750 3175);
FORCEADD HOLE..1
(775 1050);
FORCEPROP 1 LAST PART_NUMBER HOLE1187
J 0
(650 1230);
DISPLAY 0.723404 (650 1230);
PAINT GREEN (650 1230);
DISPLAY INVISIBLE (650 1230);
FORCEPROP 2 LAST PACK_TYPE TH
J 0
(650 1325);
DISPLAY 1.021277 (650 1325);
FORCEPROP 1 LAST MATERIAL EMPTY
J 0
(650 1185);
DISPLAY 0.723404 (650 1185);
PAINT GREEN (650 1185);
FORCEPROP 1 LAST $LOCATION H76
J 0
(650 1285);
DISPLAY 0.723404 (650 1285);
PAINT GREEN (650 1285);
FORCEPROP 0 LASTPIN (575 1075) $PN 1
J 2
(565 1085);
DISPLAY 0.680851 (565 1085);
PAINT MONO (565 1085);
FORCEPROP 1 LAST PATH I18
J 0
(825 1180);
DISPLAY 0.723404 (825 1180);
PAINT GREEN (825 1180);
DISPLAY INVISIBLE (825 1180);
FORCEPROP 2 LAST CDS_LIB pure_quanta
J 0
(775 1050);
DISPLAY INVISIBLE (775 1050);
FORCEPROP 1 LAST NEEDS_NO_SIZE TRUE
J 0
(775 1050);
DISPLAY 0.468085 (775 1050);
PAINT GREEN (775 1050);
DISPLAY INVISIBLE (775 1050);
FORCEPROP 0 LAST CDS_LOCATION H76
J 0
(650 1375);
DISPLAY 1.021277 (650 1375);
DISPLAY INVISIBLE (650 1375);
FORCEPROP 0 LAST $SEC 1
J 0
(650 1375);
DISPLAY 0.680851 (650 1375);
PAINT MONO (650 1375);
DISPLAY INVISIBLE (650 1375);
FORCEPROP 0 LAST CDS_SEC 1
J 0
(650 1375);
DISPLAY 1.021277 (650 1375);
DISPLAY INVISIBLE (650 1375);
FORCEADD HOLE..1
(0 750);
FORCEPROP 1 LAST PART_NUMBER HOLE1079
J 0
(-125 930);
DISPLAY 0.723404 (-125 930);
PAINT GREEN (-125 930);
DISPLAY INVISIBLE (-125 930);
FORCEPROP 1 LAST MATERIAL EMPTY
J 0
(-125 885);
DISPLAY 0.723404 (-125 885);
PAINT GREEN (-125 885);
FORCEPROP 2 LAST PACK_TYPE TH
J 0
(-125 1025);
DISPLAY 1.021277 (-125 1025);
FORCEPROP 1 LAST $LOCATION H26
J 0
(-125 985);
DISPLAY 0.723404 (-125 985);
PAINT GREEN (-125 985);
FORCEPROP 2 LASTPIN (-200 775) $PN 1
J 2
(-210 785);
DISPLAY 0.808511 (-210 785);
FORCEPROP 2 LAST CDS_LIB pure_quanta
J 0
(0 750);
PAINT MONO (0 750);
DISPLAY INVISIBLE (0 750);
FORCEPROP 1 LAST NEEDS_NO_SIZE TRUE
J 0
(0 750);
DISPLAY 0.468085 (0 750);
PAINT GREEN (0 750);
DISPLAY INVISIBLE (0 750);
FORCEPROP 1 LAST PATH I19
J 0
(50 880);
DISPLAY 0.723404 (50 880);
PAINT GREEN (50 880);
DISPLAY INVISIBLE (50 880);
FORCEPROP 2 LAST CDS_LOCATION H26
J 0
(-125 1075);
DISPLAY 1.021277 (-125 1075);
DISPLAY INVISIBLE (-125 1075);
FORCEPROP 2 LAST $SEC 1
J 0
(-125 1075);
DISPLAY 0.680851 (-125 1075);
PAINT MONO (-125 1075);
DISPLAY INVISIBLE (-125 1075);
FORCEPROP 2 LAST CDS_SEC 1
J 0
(-125 1075);
DISPLAY 1.021277 (-125 1075);
DISPLAY INVISIBLE (-125 1075);
FORCEADD HOLE..1
(3675 3550);
FORCEPROP 1 LAST PART_NUMBER HOLE596
J 0
(3550 3730);
DISPLAY 0.723404 (3550 3730);
PAINT GREEN (3550 3730);
DISPLAY INVISIBLE (3550 3730);
FORCEPROP 1 LAST MATERIAL EMPTY
J 0
(3550 3685);
DISPLAY 0.723404 (3550 3685);
PAINT GREEN (3550 3685);
FORCEPROP 2 LAST PACK_TYPE TH
J 0
(3525 4025);
DISPLAY 1.021277 (3525 4025);
FORCEPROP 1 LAST $LOCATION H106
J 0
(3550 3785);
DISPLAY 0.723404 (3550 3785);
PAINT GREEN (3550 3785);
FORCEPROP 0 LASTPIN (3475 3575) $PN 1
J 2
(3465 3585);
DISPLAY 0.680851 (3465 3585);
PAINT MONO (3465 3585);
FORCEPROP 1 LAST PATH I190
J 0
(3725 3680);
DISPLAY 0.723404 (3725 3680);
PAINT GREEN (3725 3680);
DISPLAY INVISIBLE (3725 3680);
FORCEPROP 1 LAST NEEDS_NO_SIZE TRUE
J 0
(3675 3550);
DISPLAY 0.468085 (3675 3550);
PAINT GREEN (3675 3550);
DISPLAY INVISIBLE (3675 3550);
FORCEPROP 2 LAST CDS_LIB pure_quanta
J 0
(3675 3550);
DISPLAY INVISIBLE (3675 3550);
FORCEPROP 0 LAST CDS_LOCATION H106
J 0
(3525 4075);
DISPLAY 1.021277 (3525 4075);
DISPLAY INVISIBLE (3525 4075);
FORCEPROP 0 LAST $SEC 1
J 0
(3525 4075);
DISPLAY 0.680851 (3525 4075);
PAINT MONO (3525 4075);
DISPLAY INVISIBLE (3525 4075);
FORCEPROP 0 LAST CDS_SEC 1
J 0
(3525 4075);
DISPLAY 1.021277 (3525 4075);
DISPLAY INVISIBLE (3525 4075);
FORCEADD UNIVERSAL_GND..1
(3400 3175);
FORCEPROP 3 LASTPIN (3400 3225) SIG_NAME GND\g
J 0
(3410 3235);
DISPLAY 0.659574 (3410 3235);
PAINT MONO (3410 3235);
DISPLAY INVISIBLE (3410 3235);
FORCEPROP 1 LAST HDL_POWER GND
J 1
(3425 3100);
DISPLAY 0.872340 (3425 3100);
PAINT GREEN (3425 3100);
DISPLAY INVISIBLE (3425 3100);
FORCEPROP 1 LAST PATH I191
J 0
(3475 3175);
DISPLAY 0.872340 (3475 3175);
PAINT AQUA (3475 3175);
DISPLAY INVISIBLE (3475 3175);
FORCEPROP 2 LAST CDS_LIB logical_power
J 0
(3400 3175);
DISPLAY INVISIBLE (3400 3175);
FORCEADD HOLE..1
(3675 4425);
FORCEPROP 1 LAST PART_NUMBER HOLE596
J 0
(3550 4605);
DISPLAY 0.723404 (3550 4605);
PAINT GREEN (3550 4605);
DISPLAY INVISIBLE (3550 4605);
FORCEPROP 1 LAST MATERIAL EMPTY
J 0
(3550 4560);
DISPLAY 0.723404 (3550 4560);
PAINT GREEN (3550 4560);
FORCEPROP 2 LAST PACK_TYPE TH
J 0
(3525 4900);
DISPLAY 1.021277 (3525 4900);
FORCEPROP 1 LAST $LOCATION H105
J 0
(3550 4660);
DISPLAY 0.723404 (3550 4660);
PAINT GREEN (3550 4660);
FORCEPROP 0 LASTPIN (3475 4450) $PN 1
J 2
(3465 4460);
DISPLAY 0.680851 (3465 4460);
PAINT MONO (3465 4460);
FORCEPROP 2 LAST CDS_LIB pure_quanta
J 0
(3675 4425);
DISPLAY INVISIBLE (3675 4425);
FORCEPROP 1 LAST NEEDS_NO_SIZE TRUE
J 0
(3675 4425);
DISPLAY 0.468085 (3675 4425);
PAINT GREEN (3675 4425);
DISPLAY INVISIBLE (3675 4425);
FORCEPROP 1 LAST PATH I192
J 0
(3725 4555);
DISPLAY 0.723404 (3725 4555);
PAINT GREEN (3725 4555);
DISPLAY INVISIBLE (3725 4555);
FORCEPROP 0 LAST CDS_LOCATION H105
J 0
(3525 4950);
DISPLAY 1.021277 (3525 4950);
DISPLAY INVISIBLE (3525 4950);
FORCEPROP 0 LAST $SEC 1
J 0
(3525 4950);
DISPLAY 0.680851 (3525 4950);
PAINT MONO (3525 4950);
DISPLAY INVISIBLE (3525 4950);
FORCEPROP 0 LAST CDS_SEC 1
J 0
(3525 4950);
DISPLAY 1.021277 (3525 4950);
DISPLAY INVISIBLE (3525 4950);
FORCEADD UNIVERSAL_GND..1
(3400 4050);
FORCEPROP 3 LASTPIN (3400 4100) SIG_NAME GND\g
J 0
(3410 4110);
DISPLAY 0.659574 (3410 4110);
PAINT MONO (3410 4110);
DISPLAY INVISIBLE (3410 4110);
FORCEPROP 1 LAST HDL_POWER GND
J 1
(3425 3975);
DISPLAY 0.872340 (3425 3975);
PAINT GREEN (3425 3975);
DISPLAY INVISIBLE (3425 3975);
FORCEPROP 2 LAST CDS_LIB logical_power
J 0
(3400 4050);
DISPLAY INVISIBLE (3400 4050);
FORCEPROP 1 LAST PATH I193
J 0
(3475 4050);
DISPLAY 0.872340 (3475 4050);
PAINT AQUA (3475 4050);
DISPLAY INVISIBLE (3475 4050);
FORCEADD HOLE..1
(-500 750);
FORCEPROP 1 LAST PART_NUMBER HOLE1079
J 0
(-625 930);
DISPLAY 0.723404 (-625 930);
PAINT GREEN (-625 930);
DISPLAY INVISIBLE (-625 930);
FORCEPROP 1 LAST MATERIAL EMPTY
J 0
(-625 885);
DISPLAY 0.723404 (-625 885);
PAINT GREEN (-625 885);
FORCEPROP 2 LAST PACK_TYPE TH
J 0
(-625 1025);
DISPLAY 1.021277 (-625 1025);
FORCEPROP 1 LAST $LOCATION H24
J 0
(-625 985);
DISPLAY 0.723404 (-625 985);
PAINT GREEN (-625 985);
FORCEPROP 2 LASTPIN (-700 775) $PN 1
J 2
(-710 785);
DISPLAY 0.808511 (-710 785);
FORCEPROP 2 LAST CDS_LIB pure_quanta
J 0
(-500 750);
PAINT MONO (-500 750);
DISPLAY INVISIBLE (-500 750);
FORCEPROP 1 LAST NEEDS_NO_SIZE TRUE
J 0
(-500 750);
DISPLAY 0.468085 (-500 750);
PAINT GREEN (-500 750);
DISPLAY INVISIBLE (-500 750);
FORCEPROP 1 LAST PATH I20
J 0
(-450 880);
DISPLAY 0.723404 (-450 880);
PAINT GREEN (-450 880);
DISPLAY INVISIBLE (-450 880);
FORCEPROP 2 LAST CDS_LOCATION H24
J 0
(-625 1075);
DISPLAY 1.021277 (-625 1075);
DISPLAY INVISIBLE (-625 1075);
FORCEPROP 2 LAST $SEC 1
J 0
(-625 1075);
DISPLAY 0.680851 (-625 1075);
PAINT MONO (-625 1075);
DISPLAY INVISIBLE (-625 1075);
FORCEPROP 2 LAST CDS_SEC 1
J 0
(-625 1075);
DISPLAY 1.021277 (-625 1075);
DISPLAY INVISIBLE (-625 1075);
FORCEADD GND_HOLE..1
(1350 -525);
FORCEPROP 1 LAST PART_NUMBER GND_HOLE514
J 0
(1200 -140);
DISPLAY 0.723404 (1200 -140);
PAINT GREEN (1200 -140);
DISPLAY INVISIBLE (1200 -140);
FORCEPROP 1 LAST MATERIAL EMPTY
J 0
(1200 -195);
DISPLAY 0.723404 (1200 -195);
PAINT GREEN (1200 -195);
FORCEPROP 2 LAST PACK_TYPE TH
J 0
(1200 -50);
DISPLAY 1.021277 (1200 -50);
FORCEPROP 1 LAST $LOCATION H115
J 0
(1200 -100);
DISPLAY 0.723404 (1200 -100);
PAINT GREEN (1200 -100);
FORCEPROP 0 LASTPIN (1550 -525) $PN 2
J 0
(1560 -515);
DISPLAY 0.680851 (1560 -515);
PAINT MONO (1560 -515);
FORCEPROP 0 LASTPIN (1550 -425) $PN 3
J 0
(1560 -415);
DISPLAY 0.680851 (1560 -415);
PAINT MONO (1560 -415);
FORCEPROP 0 LASTPIN (1350 -325) $PN 4
R 1
J 0
(1340 -315);
DISPLAY 0.680851 (1340 -315);
PAINT MONO (1340 -315);
FORCEPROP 0 LASTPIN (1150 -425) $PN 5
J 2
(1140 -415);
DISPLAY 0.680851 (1140 -415);
PAINT MONO (1140 -415);
FORCEPROP 0 LASTPIN (1150 -525) $PN 6
J 2
(1140 -515);
DISPLAY 0.680851 (1140 -515);
PAINT MONO (1140 -515);
FORCEPROP 0 LASTPIN (1250 -725) $PN 7
R 1
J 2
(1240 -735);
DISPLAY 0.680851 (1240 -735);
PAINT MONO (1240 -735);
FORCEPROP 0 LASTPIN (1350 -725) $PN 8
R 1
J 2
(1340 -735);
DISPLAY 0.680851 (1340 -735);
PAINT MONO (1340 -735);
FORCEPROP 0 LASTPIN (1450 -725) $PN 9
R 1
J 2
(1440 -735);
DISPLAY 0.680851 (1440 -735);
PAINT MONO (1440 -735);
FORCEPROP 2 LAST CDS_LIB pure_quanta
J 0
(1350 -525);
DISPLAY INVISIBLE (1350 -525);
FORCEPROP 1 LAST PATH I202
J 0
(1450 -215);
DISPLAY 0.723404 (1450 -215);
PAINT GREEN (1450 -215);
DISPLAY INVISIBLE (1450 -215);
FORCEPROP 1 LAST NEEDS_NO_SIZE TRUE
J 0
(1350 -525);
DISPLAY 0.468085 (1350 -525);
PAINT GREEN (1350 -525);
DISPLAY INVISIBLE (1350 -525);
FORCEPROP 0 LAST CDS_LOCATION H115
J 0
(1200 0);
DISPLAY 1.021277 (1200 0);
DISPLAY INVISIBLE (1200 0);
FORCEPROP 0 LAST $SEC 1
J 0
(1200 0);
DISPLAY 0.680851 (1200 0);
PAINT MONO (1200 0);
DISPLAY INVISIBLE (1200 0);
FORCEPROP 0 LAST CDS_SEC 1
J 0
(1200 0);
DISPLAY 1.021277 (1200 0);
DISPLAY INVISIBLE (1200 0);
FORCEADD UNIVERSAL_GND..1
(1075 -925);
FORCEPROP 3 LASTPIN (1075 -875) SIG_NAME GND\g
J 0
(1085 -865);
DISPLAY 0.659574 (1085 -865);
PAINT MONO (1085 -865);
DISPLAY INVISIBLE (1085 -865);
FORCEPROP 2 LAST CDS_LIB logical_power
J 0
(1075 -925);
DISPLAY INVISIBLE (1075 -925);
FORCEPROP 1 LAST PATH I203
J 0
(1150 -925);
DISPLAY 0.872340 (1150 -925);
PAINT AQUA (1150 -925);
DISPLAY INVISIBLE (1150 -925);
FORCEPROP 1 LAST HDL_POWER GND
J 1
(1100 -1000);
DISPLAY 0.872340 (1100 -1000);
PAINT GREEN (1100 -1000);
DISPLAY INVISIBLE (1100 -1000);
FORCEADD GND_HOLE..1
(-2325 -525);
FORCEPROP 1 LAST PART_NUMBER GND_HOLE140
J 0
(-2475 -140);
DISPLAY 0.723404 (-2475 -140);
PAINT GREEN (-2475 -140);
DISPLAY INVISIBLE (-2475 -140);
FORCEPROP 2 LAST PACK_TYPE TH
J 0
(-2475 -50);
DISPLAY 1.021277 (-2475 -50);
FORCEPROP 1 LAST MATERIAL EMPTY
J 0
(-2475 -195);
DISPLAY 0.723404 (-2475 -195);
PAINT GREEN (-2475 -195);
FORCEPROP 1 LAST $LOCATION H111
J 0
(-2475 -100);
DISPLAY 0.723404 (-2475 -100);
PAINT GREEN (-2475 -100);
FORCEPROP 0 LASTPIN (-2125 -525) $PN 2
J 0
(-2115 -515);
DISPLAY 0.680851 (-2115 -515);
PAINT MONO (-2115 -515);
FORCEPROP 0 LASTPIN (-2125 -425) $PN 3
J 0
(-2115 -415);
DISPLAY 0.680851 (-2115 -415);
PAINT MONO (-2115 -415);
FORCEPROP 0 LASTPIN (-2325 -325) $PN 4
R 1
J 0
(-2335 -315);
DISPLAY 0.680851 (-2335 -315);
PAINT MONO (-2335 -315);
FORCEPROP 0 LASTPIN (-2525 -425) $PN 5
J 2
(-2535 -415);
DISPLAY 0.680851 (-2535 -415);
PAINT MONO (-2535 -415);
FORCEPROP 0 LASTPIN (-2525 -525) $PN 6
J 2
(-2535 -515);
DISPLAY 0.680851 (-2535 -515);
PAINT MONO (-2535 -515);
FORCEPROP 0 LASTPIN (-2425 -725) $PN 7
R 1
J 2
(-2435 -735);
DISPLAY 0.680851 (-2435 -735);
PAINT MONO (-2435 -735);
FORCEPROP 0 LASTPIN (-2325 -725) $PN 8
R 1
J 2
(-2335 -735);
DISPLAY 0.680851 (-2335 -735);
PAINT MONO (-2335 -735);
FORCEPROP 0 LASTPIN (-2225 -725) $PN 9
R 1
J 2
(-2235 -735);
DISPLAY 0.680851 (-2235 -735);
PAINT MONO (-2235 -735);
FORCEPROP 1 LAST PATH I204
J 0
(-2225 -215);
DISPLAY 0.723404 (-2225 -215);
PAINT GREEN (-2225 -215);
DISPLAY INVISIBLE (-2225 -215);
FORCEPROP 1 LAST NEEDS_NO_SIZE TRUE
J 0
(-2325 -525);
DISPLAY 0.468085 (-2325 -525);
PAINT GREEN (-2325 -525);
DISPLAY INVISIBLE (-2325 -525);
FORCEPROP 2 LAST CDS_LIB pure_quanta
J 0
(-2325 -525);
DISPLAY INVISIBLE (-2325 -525);
FORCEPROP 0 LAST CDS_LOCATION H111
J 0
(-2475 0);
DISPLAY 1.021277 (-2475 0);
DISPLAY INVISIBLE (-2475 0);
FORCEPROP 0 LAST $SEC 1
J 0
(-2475 0);
DISPLAY 0.680851 (-2475 0);
PAINT MONO (-2475 0);
DISPLAY INVISIBLE (-2475 0);
FORCEPROP 0 LAST CDS_SEC 1
J 0
(-2475 0);
DISPLAY 1.021277 (-2475 0);
DISPLAY INVISIBLE (-2475 0);
FORCEADD UNIVERSAL_GND..1
(-2600 -925);
FORCEPROP 3 LASTPIN (-2600 -875) SIG_NAME GND\g
J 0
(-2590 -865);
DISPLAY 0.659574 (-2590 -865);
PAINT MONO (-2590 -865);
DISPLAY INVISIBLE (-2590 -865);
FORCEPROP 1 LAST PATH I205
J 0
(-2525 -925);
DISPLAY 0.872340 (-2525 -925);
PAINT AQUA (-2525 -925);
DISPLAY INVISIBLE (-2525 -925);
FORCEPROP 1 LAST HDL_POWER GND
J 1
(-2575 -1000);
DISPLAY 0.872340 (-2575 -1000);
PAINT GREEN (-2575 -1000);
DISPLAY INVISIBLE (-2575 -1000);
FORCEPROP 2 LAST CDS_LIB logical_power
J 0
(-2600 -925);
DISPLAY INVISIBLE (-2600 -925);
FORCEADD UNIVERSAL_GND..1
(-1825 -925);
FORCEPROP 3 LASTPIN (-1825 -875) SIG_NAME GND\g
J 0
(-1815 -865);
DISPLAY 0.659574 (-1815 -865);
PAINT MONO (-1815 -865);
DISPLAY INVISIBLE (-1815 -865);
FORCEPROP 1 LAST PATH I206
J 0
(-1750 -925);
DISPLAY 0.872340 (-1750 -925);
PAINT AQUA (-1750 -925);
DISPLAY INVISIBLE (-1750 -925);
FORCEPROP 2 LAST CDS_LIB logical_power
J 0
(-1825 -925);
DISPLAY INVISIBLE (-1825 -925);
FORCEPROP 1 LAST HDL_POWER GND
J 1
(-1800 -1000);
DISPLAY 0.872340 (-1800 -1000);
PAINT GREEN (-1800 -1000);
DISPLAY INVISIBLE (-1800 -1000);
FORCEADD GND_HOLE..1
(-1550 -525);
FORCEPROP 1 LAST PART_NUMBER GND_HOLE140
J 0
(-1700 -140);
DISPLAY 0.723404 (-1700 -140);
PAINT GREEN (-1700 -140);
DISPLAY INVISIBLE (-1700 -140);
FORCEPROP 1 LAST MATERIAL EMPTY
J 0
(-1700 -195);
DISPLAY 0.723404 (-1700 -195);
PAINT GREEN (-1700 -195);
FORCEPROP 2 LAST PACK_TYPE TH
J 0
(-1700 -50);
DISPLAY 1.021277 (-1700 -50);
FORCEPROP 1 LAST $LOCATION H112
J 0
(-1700 -100);
DISPLAY 0.723404 (-1700 -100);
PAINT GREEN (-1700 -100);
FORCEPROP 0 LASTPIN (-1350 -525) $PN 2
J 0
(-1340 -515);
DISPLAY 0.680851 (-1340 -515);
PAINT MONO (-1340 -515);
FORCEPROP 0 LASTPIN (-1350 -425) $PN 3
J 0
(-1340 -415);
DISPLAY 0.680851 (-1340 -415);
PAINT MONO (-1340 -415);
FORCEPROP 0 LASTPIN (-1550 -325) $PN 4
R 1
J 0
(-1560 -315);
DISPLAY 0.680851 (-1560 -315);
PAINT MONO (-1560 -315);
FORCEPROP 0 LASTPIN (-1750 -425) $PN 5
J 2
(-1760 -415);
DISPLAY 0.680851 (-1760 -415);
PAINT MONO (-1760 -415);
FORCEPROP 0 LASTPIN (-1750 -525) $PN 6
J 2
(-1760 -515);
DISPLAY 0.680851 (-1760 -515);
PAINT MONO (-1760 -515);
FORCEPROP 0 LASTPIN (-1650 -725) $PN 7
R 1
J 2
(-1660 -735);
DISPLAY 0.680851 (-1660 -735);
PAINT MONO (-1660 -735);
FORCEPROP 0 LASTPIN (-1550 -725) $PN 8
R 1
J 2
(-1560 -735);
DISPLAY 0.680851 (-1560 -735);
PAINT MONO (-1560 -735);
FORCEPROP 0 LASTPIN (-1450 -725) $PN 9
R 1
J 2
(-1460 -735);
DISPLAY 0.680851 (-1460 -735);
PAINT MONO (-1460 -735);
FORCEPROP 1 LAST PATH I207
J 0
(-1450 -215);
DISPLAY 0.723404 (-1450 -215);
PAINT GREEN (-1450 -215);
DISPLAY INVISIBLE (-1450 -215);
FORCEPROP 2 LAST CDS_LIB pure_quanta
J 0
(-1550 -525);
DISPLAY INVISIBLE (-1550 -525);
FORCEPROP 1 LAST NEEDS_NO_SIZE TRUE
J 0
(-1550 -525);
DISPLAY 0.468085 (-1550 -525);
PAINT GREEN (-1550 -525);
DISPLAY INVISIBLE (-1550 -525);
FORCEPROP 0 LAST CDS_LOCATION H112
J 0
(-1700 0);
DISPLAY 1.021277 (-1700 0);
DISPLAY INVISIBLE (-1700 0);
FORCEPROP 0 LAST $SEC 1
J 0
(-1700 0);
DISPLAY 0.680851 (-1700 0);
PAINT MONO (-1700 0);
DISPLAY INVISIBLE (-1700 0);
FORCEPROP 0 LAST CDS_SEC 1
J 0
(-1700 0);
DISPLAY 1.021277 (-1700 0);
DISPLAY INVISIBLE (-1700 0);
FORCEADD HOLE..1
(-1025 750);
FORCEPROP 1 LAST PART_NUMBER HOLE1079
J 0
(-1150 930);
DISPLAY 0.723404 (-1150 930);
PAINT GREEN (-1150 930);
DISPLAY INVISIBLE (-1150 930);
FORCEPROP 1 LAST MATERIAL EMPTY
J 0
(-1150 885);
DISPLAY 0.723404 (-1150 885);
PAINT GREEN (-1150 885);
FORCEPROP 2 LAST PACK_TYPE TH
J 0
(-1150 1025);
DISPLAY 1.021277 (-1150 1025);
FORCEPROP 1 LAST $LOCATION H22
J 0
(-1150 985);
DISPLAY 0.723404 (-1150 985);
PAINT GREEN (-1150 985);
FORCEPROP 2 LASTPIN (-1225 775) $PN 1
J 2
(-1235 785);
DISPLAY 0.808511 (-1235 785);
FORCEPROP 2 LAST CDS_LIB pure_quanta
J 0
(-1025 750);
PAINT MONO (-1025 750);
DISPLAY INVISIBLE (-1025 750);
FORCEPROP 1 LAST NEEDS_NO_SIZE TRUE
J 0
(-1025 750);
DISPLAY 0.468085 (-1025 750);
PAINT GREEN (-1025 750);
DISPLAY INVISIBLE (-1025 750);
FORCEPROP 1 LAST PATH I21
J 0
(-975 880);
DISPLAY 0.723404 (-975 880);
PAINT GREEN (-975 880);
DISPLAY INVISIBLE (-975 880);
FORCEPROP 2 LAST CDS_LOCATION H22
J 0
(-1150 1075);
DISPLAY 1.021277 (-1150 1075);
DISPLAY INVISIBLE (-1150 1075);
FORCEPROP 2 LAST $SEC 1
J 0
(-1150 1075);
DISPLAY 0.680851 (-1150 1075);
PAINT MONO (-1150 1075);
DISPLAY INVISIBLE (-1150 1075);
FORCEPROP 2 LAST CDS_SEC 1
J 0
(-1150 1075);
DISPLAY 1.021277 (-1150 1075);
DISPLAY INVISIBLE (-1150 1075);
FORCEADD HOLE..1
(-2450 2250);
FORCEPROP 1 LAST PART_NUMBER SP_HOLE1199
J 0
(-2575 2430);
DISPLAY 0.723404 (-2575 2430);
PAINT GREEN (-2575 2430);
DISPLAY INVISIBLE (-2575 2430);
FORCEPROP 1 LAST MATERIAL EMPTY
J 0
(-2575 2385);
DISPLAY 0.723404 (-2575 2385);
PAINT GREEN (-2575 2385);
FORCEPROP 2 LAST PACK_TYPE TH
J 0
(-2575 2525);
DISPLAY 1.021277 (-2575 2525);
FORCEPROP 1 LAST LOCATION H44
J 0
(-2575 2485);
DISPLAY 0.723404 (-2575 2485);
PAINT GREEN (-2575 2485);
FORCEPROP 0 LASTPIN (-2650 2275) $PN 1
J 2
(-2660 2285);
DISPLAY 0.680851 (-2660 2285);
PAINT MONO (-2660 2285);
FORCEPROP 1 LAST NEEDS_NO_SIZE TRUE
J 0
(-2450 2250);
DISPLAY 0.468085 (-2450 2250);
PAINT GREEN (-2450 2250);
DISPLAY INVISIBLE (-2450 2250);
FORCEPROP 1 LAST PATH I216
J 0
(-2400 2380);
DISPLAY 0.723404 (-2400 2380);
PAINT GREEN (-2400 2380);
DISPLAY INVISIBLE (-2400 2380);
FORCEPROP 2 LAST CDS_LIB pure_quanta
J 0
(-2450 2250);
DISPLAY INVISIBLE (-2450 2250);
FORCEPROP 0 LAST $SEC 1
J 0
(-2575 2575);
DISPLAY 0.680851 (-2575 2575);
PAINT MONO (-2575 2575);
DISPLAY INVISIBLE (-2575 2575);
FORCEPROP 0 LAST CDS_SEC 1
J 0
(-2575 2575);
DISPLAY 1.021277 (-2575 2575);
DISPLAY INVISIBLE (-2575 2575);
FORCEADD HOLE..1
(-1825 2250);
FORCEPROP 1 LAST PART_NUMBER SP_HOLE1199
J 0
(-1950 2430);
DISPLAY 0.723404 (-1950 2430);
PAINT GREEN (-1950 2430);
DISPLAY INVISIBLE (-1950 2430);
FORCEPROP 1 LAST MATERIAL EMPTY
J 0
(-1950 2385);
DISPLAY 0.723404 (-1950 2385);
PAINT GREEN (-1950 2385);
FORCEPROP 2 LAST PACK_TYPE TH
J 0
(-1950 2525);
DISPLAY 1.021277 (-1950 2525);
FORCEPROP 1 LAST LOCATION H45
J 0
(-1950 2485);
DISPLAY 0.723404 (-1950 2485);
PAINT GREEN (-1950 2485);
FORCEPROP 0 LASTPIN (-2025 2275) $PN 1
J 2
(-2035 2285);
DISPLAY 0.680851 (-2035 2285);
PAINT MONO (-2035 2285);
FORCEPROP 2 LAST CDS_LIB pure_quanta
J 0
(-1825 2250);
DISPLAY INVISIBLE (-1825 2250);
FORCEPROP 1 LAST PATH I217
J 0
(-1775 2380);
DISPLAY 0.723404 (-1775 2380);
PAINT GREEN (-1775 2380);
DISPLAY INVISIBLE (-1775 2380);
FORCEPROP 1 LAST NEEDS_NO_SIZE TRUE
J 0
(-1825 2250);
DISPLAY 0.468085 (-1825 2250);
PAINT GREEN (-1825 2250);
DISPLAY INVISIBLE (-1825 2250);
FORCEPROP 0 LAST $SEC 1
J 0
(-1950 2575);
DISPLAY 0.680851 (-1950 2575);
PAINT MONO (-1950 2575);
DISPLAY INVISIBLE (-1950 2575);
FORCEPROP 0 LAST CDS_SEC 1
J 0
(-1950 2575);
DISPLAY 1.021277 (-1950 2575);
DISPLAY INVISIBLE (-1950 2575);
FORCEADD HOLE..1
(-1175 2250);
FORCEPROP 1 LAST PART_NUMBER SP_HOLE1199
J 0
(-1300 2430);
DISPLAY 0.723404 (-1300 2430);
PAINT GREEN (-1300 2430);
DISPLAY INVISIBLE (-1300 2430);
FORCEPROP 2 LAST PACK_TYPE TH
J 0
(-1300 2525);
DISPLAY 1.021277 (-1300 2525);
FORCEPROP 1 LAST MATERIAL EMPTY
J 0
(-1300 2385);
DISPLAY 0.723404 (-1300 2385);
PAINT GREEN (-1300 2385);
FORCEPROP 1 LAST LOCATION H47
J 0
(-1300 2485);
DISPLAY 0.723404 (-1300 2485);
PAINT GREEN (-1300 2485);
FORCEPROP 0 LASTPIN (-1375 2275) $PN 1
J 2
(-1385 2285);
DISPLAY 0.680851 (-1385 2285);
PAINT MONO (-1385 2285);
FORCEPROP 1 LAST NEEDS_NO_SIZE TRUE
J 0
(-1175 2250);
DISPLAY 0.468085 (-1175 2250);
PAINT GREEN (-1175 2250);
DISPLAY INVISIBLE (-1175 2250);
FORCEPROP 1 LAST PATH I218
J 0
(-1125 2380);
DISPLAY 0.723404 (-1125 2380);
PAINT GREEN (-1125 2380);
DISPLAY INVISIBLE (-1125 2380);
FORCEPROP 2 LAST CDS_LIB pure_quanta
J 0
(-1175 2250);
DISPLAY INVISIBLE (-1175 2250);
FORCEPROP 0 LAST $SEC 1
J 0
(-1300 2575);
DISPLAY 0.680851 (-1300 2575);
PAINT MONO (-1300 2575);
DISPLAY INVISIBLE (-1300 2575);
FORCEPROP 0 LAST CDS_SEC 1
J 0
(-1300 2575);
DISPLAY 1.021277 (-1300 2575);
DISPLAY INVISIBLE (-1300 2575);
FORCEADD HOLE..1
(-525 2250);
FORCEPROP 1 LAST PART_NUMBER SP_HOLE1199
J 0
(-650 2430);
DISPLAY 0.723404 (-650 2430);
PAINT GREEN (-650 2430);
DISPLAY INVISIBLE (-650 2430);
FORCEPROP 1 LAST MATERIAL EMPTY
J 0
(-650 2385);
DISPLAY 0.723404 (-650 2385);
PAINT GREEN (-650 2385);
FORCEPROP 2 LAST PACK_TYPE TH
J 0
(-650 2525);
DISPLAY 1.021277 (-650 2525);
FORCEPROP 1 LAST LOCATION H49
J 0
(-650 2485);
DISPLAY 0.723404 (-650 2485);
PAINT GREEN (-650 2485);
FORCEPROP 0 LASTPIN (-725 2275) $PN 1
J 2
(-735 2285);
DISPLAY 0.680851 (-735 2285);
PAINT MONO (-735 2285);
FORCEPROP 2 LAST CDS_LIB pure_quanta
J 0
(-525 2250);
DISPLAY INVISIBLE (-525 2250);
FORCEPROP 1 LAST PATH I219
J 0
(-475 2380);
DISPLAY 0.723404 (-475 2380);
PAINT GREEN (-475 2380);
DISPLAY INVISIBLE (-475 2380);
FORCEPROP 1 LAST NEEDS_NO_SIZE TRUE
J 0
(-525 2250);
DISPLAY 0.468085 (-525 2250);
PAINT GREEN (-525 2250);
DISPLAY INVISIBLE (-525 2250);
FORCEPROP 0 LAST $SEC 1
J 0
(-650 2575);
DISPLAY 0.680851 (-650 2575);
PAINT MONO (-650 2575);
DISPLAY INVISIBLE (-650 2575);
FORCEPROP 0 LAST CDS_SEC 1
J 0
(-650 2575);
DISPLAY 1.021277 (-650 2575);
DISPLAY INVISIBLE (-650 2575);
FORCEADD UNIVERSAL_GND..1
(-2725 2100);
FORCEPROP 3 LASTPIN (-2725 2150) SIG_NAME GND\g
J 0
(-2715 2160);
DISPLAY 0.659574 (-2715 2160);
PAINT MONO (-2715 2160);
DISPLAY INVISIBLE (-2715 2160);
FORCEPROP 2 LAST CDS_LIB logical_power
J 0
(-2725 2100);
DISPLAY INVISIBLE (-2725 2100);
FORCEPROP 1 LAST PATH I220
J 0
(-2650 2100);
DISPLAY 0.872340 (-2650 2100);
PAINT AQUA (-2650 2100);
DISPLAY INVISIBLE (-2650 2100);
FORCEPROP 1 LAST HDL_POWER GND
J 1
(-2700 2025);
DISPLAY 0.872340 (-2700 2025);
PAINT GREEN (-2700 2025);
DISPLAY INVISIBLE (-2700 2025);
FORCEADD UNIVERSAL_GND..1
(-2100 2100);
FORCEPROP 3 LASTPIN (-2100 2150) SIG_NAME GND\g
J 0
(-2090 2160);
DISPLAY 0.659574 (-2090 2160);
PAINT MONO (-2090 2160);
DISPLAY INVISIBLE (-2090 2160);
FORCEPROP 2 LAST CDS_LIB logical_power
J 0
(-2100 2100);
DISPLAY INVISIBLE (-2100 2100);
FORCEPROP 1 LAST PATH I221
J 0
(-2025 2100);
DISPLAY 0.872340 (-2025 2100);
PAINT AQUA (-2025 2100);
DISPLAY INVISIBLE (-2025 2100);
FORCEPROP 1 LAST HDL_POWER GND
J 1
(-2075 2025);
DISPLAY 0.872340 (-2075 2025);
PAINT GREEN (-2075 2025);
DISPLAY INVISIBLE (-2075 2025);
FORCEADD UNIVERSAL_GND..1
(-1450 2100);
FORCEPROP 3 LASTPIN (-1450 2150) SIG_NAME GND\g
J 0
(-1440 2160);
DISPLAY 0.659574 (-1440 2160);
PAINT MONO (-1440 2160);
DISPLAY INVISIBLE (-1440 2160);
FORCEPROP 1 LAST HDL_POWER GND
J 1
(-1425 2025);
DISPLAY 0.872340 (-1425 2025);
PAINT GREEN (-1425 2025);
DISPLAY INVISIBLE (-1425 2025);
FORCEPROP 1 LAST PATH I222
J 0
(-1375 2100);
DISPLAY 0.872340 (-1375 2100);
PAINT AQUA (-1375 2100);
DISPLAY INVISIBLE (-1375 2100);
FORCEPROP 2 LAST CDS_LIB logical_power
J 0
(-1450 2100);
DISPLAY INVISIBLE (-1450 2100);
FORCEADD UNIVERSAL_GND..1
(-800 2100);
FORCEPROP 3 LASTPIN (-800 2150) SIG_NAME GND\g
J 0
(-790 2160);
DISPLAY 0.659574 (-790 2160);
PAINT MONO (-790 2160);
DISPLAY INVISIBLE (-790 2160);
FORCEPROP 1 LAST HDL_POWER GND
J 1
(-775 2025);
DISPLAY 0.872340 (-775 2025);
PAINT GREEN (-775 2025);
DISPLAY INVISIBLE (-775 2025);
FORCEPROP 1 LAST PATH I223
J 0
(-725 2100);
DISPLAY 0.872340 (-725 2100);
PAINT AQUA (-725 2100);
DISPLAY INVISIBLE (-725 2100);
FORCEPROP 2 LAST CDS_LIB logical_power
J 0
(-800 2100);
DISPLAY INVISIBLE (-800 2100);
FORCEADD HOLE..1
(2750 -825);
FORCEPROP 1 LAST PART_NUMBER TMP-C_T2I_ALEX_1121_1
J 0
(2625 -645);
DISPLAY 0.723404 (2625 -645);
PAINT GREEN (2625 -645);
DISPLAY INVISIBLE (2625 -645);
FORCEPROP 2 LAST PACK_TYPE TH
J 0
(2625 -550);
DISPLAY 1.021277 (2625 -550);
FORCEPROP 1 LAST MATERIAL EMPTY
J 0
(2625 -690);
DISPLAY 0.723404 (2625 -690);
PAINT GREEN (2625 -690);
FORCEPROP 1 LAST $LOCATION H120
J 0
(2625 -590);
DISPLAY 0.723404 (2625 -590);
PAINT GREEN (2625 -590);
FORCEPROP 0 LASTPIN (2550 -800) $PN 1
J 2
(2540 -790);
DISPLAY 0.680851 (2540 -790);
PAINT MONO (2540 -790);
FORCEPROP 2 LAST CDS_LIB pure_quanta
J 0
(2750 -825);
DISPLAY INVISIBLE (2750 -825);
FORCEPROP 1 LAST PATH I224
J 0
(2800 -695);
DISPLAY 0.723404 (2800 -695);
PAINT GREEN (2800 -695);
DISPLAY INVISIBLE (2800 -695);
FORCEPROP 1 LAST NEEDS_NO_SIZE TRUE
J 0
(2750 -825);
DISPLAY 0.468085 (2750 -825);
PAINT GREEN (2750 -825);
DISPLAY INVISIBLE (2750 -825);
FORCEPROP 0 LAST CDS_LOCATION H120
J 0
(2625 -500);
DISPLAY 1.021277 (2625 -500);
DISPLAY INVISIBLE (2625 -500);
FORCEPROP 0 LAST $SEC 1
J 0
(2625 -500);
DISPLAY 0.680851 (2625 -500);
PAINT MONO (2625 -500);
DISPLAY INVISIBLE (2625 -500);
FORCEPROP 0 LAST CDS_SEC 1
J 0
(2625 -500);
DISPLAY 1.021277 (2625 -500);
DISPLAY INVISIBLE (2625 -500);
FORCEADD HOLE..1
(3500 -850);
FORCEPROP 1 LAST PART_NUMBER TMP-C_T2I_ALEX_1121_1
J 0
(3375 -670);
DISPLAY 0.723404 (3375 -670);
PAINT GREEN (3375 -670);
DISPLAY INVISIBLE (3375 -670);
FORCEPROP 2 LAST PACK_TYPE TH
J 0
(3375 -575);
DISPLAY 1.021277 (3375 -575);
FORCEPROP 1 LAST MATERIAL EMPTY
J 0
(3375 -715);
DISPLAY 0.723404 (3375 -715);
PAINT GREEN (3375 -715);
FORCEPROP 1 LAST $LOCATION H122
J 0
(3375 -615);
DISPLAY 0.723404 (3375 -615);
PAINT GREEN (3375 -615);
FORCEPROP 0 LASTPIN (3300 -825) $PN 1
J 2
(3290 -815);
DISPLAY 0.680851 (3290 -815);
PAINT MONO (3290 -815);
FORCEPROP 1 LAST NEEDS_NO_SIZE TRUE
J 0
(3500 -850);
DISPLAY 0.468085 (3500 -850);
PAINT GREEN (3500 -850);
DISPLAY INVISIBLE (3500 -850);
FORCEPROP 1 LAST PATH I225
J 0
(3550 -720);
DISPLAY 0.723404 (3550 -720);
PAINT GREEN (3550 -720);
DISPLAY INVISIBLE (3550 -720);
FORCEPROP 2 LAST CDS_LIB pure_quanta
J 0
(3500 -850);
DISPLAY INVISIBLE (3500 -850);
FORCEPROP 0 LAST CDS_LOCATION H122
J 0
(3375 -525);
DISPLAY 1.021277 (3375 -525);
DISPLAY INVISIBLE (3375 -525);
FORCEPROP 0 LAST $SEC 1
J 0
(3375 -525);
DISPLAY 0.680851 (3375 -525);
PAINT MONO (3375 -525);
DISPLAY INVISIBLE (3375 -525);
FORCEPROP 0 LAST CDS_SEC 1
J 0
(3375 -525);
DISPLAY 1.021277 (3375 -525);
DISPLAY INVISIBLE (3375 -525);
FORCEADD HOLE..1
(4275 -850);
FORCEPROP 1 LAST PART_NUMBER TMP-C_T2I_ALEX_1121_1
J 0
(4150 -670);
DISPLAY 0.723404 (4150 -670);
PAINT GREEN (4150 -670);
DISPLAY INVISIBLE (4150 -670);
FORCEPROP 2 LAST PACK_TYPE TH
J 0
(4150 -575);
DISPLAY 1.021277 (4150 -575);
FORCEPROP 1 LAST MATERIAL EMPTY
J 0
(4150 -715);
DISPLAY 0.723404 (4150 -715);
PAINT GREEN (4150 -715);
FORCEPROP 1 LAST $LOCATION H124
J 0
(4150 -615);
DISPLAY 0.723404 (4150 -615);
PAINT GREEN (4150 -615);
FORCEPROP 0 LASTPIN (4075 -825) $PN 1
J 2
(4065 -815);
DISPLAY 0.680851 (4065 -815);
PAINT MONO (4065 -815);
FORCEPROP 1 LAST NEEDS_NO_SIZE TRUE
J 0
(4275 -850);
DISPLAY 0.468085 (4275 -850);
PAINT GREEN (4275 -850);
DISPLAY INVISIBLE (4275 -850);
FORCEPROP 1 LAST PATH I226
J 0
(4325 -720);
DISPLAY 0.723404 (4325 -720);
PAINT GREEN (4325 -720);
DISPLAY INVISIBLE (4325 -720);
FORCEPROP 2 LAST CDS_LIB pure_quanta
J 0
(4275 -850);
DISPLAY INVISIBLE (4275 -850);
FORCEPROP 0 LAST CDS_LOCATION H124
J 0
(4150 -525);
DISPLAY 1.021277 (4150 -525);
DISPLAY INVISIBLE (4150 -525);
FORCEPROP 0 LAST $SEC 1
J 0
(4150 -525);
DISPLAY 0.680851 (4150 -525);
PAINT MONO (4150 -525);
DISPLAY INVISIBLE (4150 -525);
FORCEPROP 0 LAST CDS_SEC 1
J 0
(4150 -525);
DISPLAY 1.021277 (4150 -525);
DISPLAY INVISIBLE (4150 -525);
FORCEADD HOLE..1
(5050 -850);
FORCEPROP 1 LAST PART_NUMBER TMP-C_T2I_ALEX_1121_1
J 0
(4925 -670);
DISPLAY 0.723404 (4925 -670);
PAINT GREEN (4925 -670);
DISPLAY INVISIBLE (4925 -670);
FORCEPROP 2 LAST PACK_TYPE TH
J 0
(4925 -575);
DISPLAY 1.021277 (4925 -575);
FORCEPROP 1 LAST MATERIAL EMPTY
J 0
(4925 -715);
DISPLAY 0.723404 (4925 -715);
PAINT GREEN (4925 -715);
FORCEPROP 1 LAST $LOCATION H126
J 0
(4925 -615);
DISPLAY 0.723404 (4925 -615);
PAINT GREEN (4925 -615);
FORCEPROP 0 LASTPIN (4850 -825) $PN 1
J 2
(4840 -815);
DISPLAY 0.680851 (4840 -815);
PAINT MONO (4840 -815);
FORCEPROP 1 LAST NEEDS_NO_SIZE TRUE
J 0
(5050 -850);
DISPLAY 0.468085 (5050 -850);
PAINT GREEN (5050 -850);
DISPLAY INVISIBLE (5050 -850);
FORCEPROP 1 LAST PATH I227
J 0
(5100 -720);
DISPLAY 0.723404 (5100 -720);
PAINT GREEN (5100 -720);
DISPLAY INVISIBLE (5100 -720);
FORCEPROP 2 LAST CDS_LIB pure_quanta
J 0
(5050 -850);
DISPLAY INVISIBLE (5050 -850);
FORCEPROP 0 LAST CDS_LOCATION H126
J 0
(4925 -525);
DISPLAY 1.021277 (4925 -525);
DISPLAY INVISIBLE (4925 -525);
FORCEPROP 0 LAST $SEC 1
J 0
(4925 -525);
DISPLAY 0.680851 (4925 -525);
PAINT MONO (4925 -525);
DISPLAY INVISIBLE (4925 -525);
FORCEPROP 0 LAST CDS_SEC 1
J 0
(4925 -525);
DISPLAY 1.021277 (4925 -525);
DISPLAY INVISIBLE (4925 -525);
FORCEADD HOLE..1
(5075 -375);
FORCEPROP 1 LAST PART_NUMBER TMP-C_T2I_ALEX_1121_1
J 0
(4950 -195);
DISPLAY 0.723404 (4950 -195);
PAINT GREEN (4950 -195);
DISPLAY INVISIBLE (4950 -195);
FORCEPROP 1 LAST MATERIAL EMPTY
J 0
(4950 -240);
DISPLAY 0.723404 (4950 -240);
PAINT GREEN (4950 -240);
FORCEPROP 2 LAST PACK_TYPE TH
J 0
(4950 -100);
DISPLAY 1.021277 (4950 -100);
FORCEPROP 1 LAST $LOCATION H127
J 0
(4950 -140);
DISPLAY 0.723404 (4950 -140);
PAINT GREEN (4950 -140);
FORCEPROP 0 LASTPIN (4875 -350) $PN 1
J 2
(4865 -340);
DISPLAY 0.680851 (4865 -340);
PAINT MONO (4865 -340);
FORCEPROP 2 LAST CDS_LIB pure_quanta
J 0
(5075 -375);
DISPLAY INVISIBLE (5075 -375);
FORCEPROP 1 LAST PATH I228
J 0
(5125 -245);
DISPLAY 0.723404 (5125 -245);
PAINT GREEN (5125 -245);
DISPLAY INVISIBLE (5125 -245);
FORCEPROP 1 LAST NEEDS_NO_SIZE TRUE
J 0
(5075 -375);
DISPLAY 0.468085 (5075 -375);
PAINT GREEN (5075 -375);
DISPLAY INVISIBLE (5075 -375);
FORCEPROP 0 LAST CDS_LOCATION H127
J 0
(4950 -50);
DISPLAY 1.021277 (4950 -50);
DISPLAY INVISIBLE (4950 -50);
FORCEPROP 0 LAST $SEC 1
J 0
(4950 -50);
DISPLAY 0.680851 (4950 -50);
PAINT MONO (4950 -50);
DISPLAY INVISIBLE (4950 -50);
FORCEPROP 0 LAST CDS_SEC 1
J 0
(4950 -50);
DISPLAY 1.021277 (4950 -50);
DISPLAY INVISIBLE (4950 -50);
FORCEADD HOLE..1
(4300 -375);
FORCEPROP 1 LAST PART_NUMBER TMP-C_T2I_ALEX_1121_1
J 0
(4175 -195);
DISPLAY 0.723404 (4175 -195);
PAINT GREEN (4175 -195);
DISPLAY INVISIBLE (4175 -195);
FORCEPROP 1 LAST MATERIAL EMPTY
J 0
(4175 -240);
DISPLAY 0.723404 (4175 -240);
PAINT GREEN (4175 -240);
FORCEPROP 2 LAST PACK_TYPE TH
J 0
(4175 -100);
DISPLAY 1.021277 (4175 -100);
FORCEPROP 1 LAST $LOCATION H125
J 0
(4175 -140);
DISPLAY 0.723404 (4175 -140);
PAINT GREEN (4175 -140);
FORCEPROP 0 LASTPIN (4100 -350) $PN 1
J 2
(4090 -340);
DISPLAY 0.680851 (4090 -340);
PAINT MONO (4090 -340);
FORCEPROP 2 LAST CDS_LIB pure_quanta
J 0
(4300 -375);
DISPLAY INVISIBLE (4300 -375);
FORCEPROP 1 LAST PATH I229
J 0
(4350 -245);
DISPLAY 0.723404 (4350 -245);
PAINT GREEN (4350 -245);
DISPLAY INVISIBLE (4350 -245);
FORCEPROP 1 LAST NEEDS_NO_SIZE TRUE
J 0
(4300 -375);
DISPLAY 0.468085 (4300 -375);
PAINT GREEN (4300 -375);
DISPLAY INVISIBLE (4300 -375);
FORCEPROP 0 LAST CDS_LOCATION H125
J 0
(4175 -50);
DISPLAY 1.021277 (4175 -50);
DISPLAY INVISIBLE (4175 -50);
FORCEPROP 0 LAST $SEC 1
J 0
(4175 -50);
DISPLAY 0.680851 (4175 -50);
PAINT MONO (4175 -50);
DISPLAY INVISIBLE (4175 -50);
FORCEPROP 0 LAST CDS_SEC 1
J 0
(4175 -50);
DISPLAY 1.021277 (4175 -50);
DISPLAY INVISIBLE (4175 -50);
FORCEADD HOLE..1
(4350 4425);
FORCEPROP 1 LAST PART_NUMBER HOLE596
J 0
(4225 4605);
DISPLAY 0.723404 (4225 4605);
PAINT GREEN (4225 4605);
DISPLAY INVISIBLE (4225 4605);
FORCEPROP 1 LAST MATERIAL EMPTY
J 0
(4225 4560);
DISPLAY 0.723404 (4225 4560);
PAINT GREEN (4225 4560);
FORCEPROP 2 LAST PACK_TYPE TH
J 0
(4200 4900);
DISPLAY 1.021277 (4200 4900);
FORCEPROP 1 LAST $LOCATION H128
J 0
(4225 4660);
DISPLAY 0.723404 (4225 4660);
PAINT GREEN (4225 4660);
FORCEPROP 0 LASTPIN (4150 4450) $PN 1
J 2
(4140 4460);
DISPLAY 0.680851 (4140 4460);
PAINT MONO (4140 4460);
FORCEPROP 1 LAST PATH I232
J 0
(4400 4555);
DISPLAY 0.723404 (4400 4555);
PAINT GREEN (4400 4555);
DISPLAY INVISIBLE (4400 4555);
FORCEPROP 1 LAST NEEDS_NO_SIZE TRUE
J 0
(4350 4425);
DISPLAY 0.468085 (4350 4425);
PAINT GREEN (4350 4425);
DISPLAY INVISIBLE (4350 4425);
FORCEPROP 2 LAST CDS_LIB pure_quanta
J 0
(4350 4425);
DISPLAY INVISIBLE (4350 4425);
FORCEPROP 0 LAST CDS_LOCATION H128
J 0
(4200 4950);
DISPLAY 1.021277 (4200 4950);
DISPLAY INVISIBLE (4200 4950);
FORCEPROP 0 LAST $SEC 1
J 0
(4200 4950);
DISPLAY 0.680851 (4200 4950);
PAINT MONO (4200 4950);
DISPLAY INVISIBLE (4200 4950);
FORCEPROP 0 LAST CDS_SEC 1
J 0
(4200 4950);
DISPLAY 1.021277 (4200 4950);
DISPLAY INVISIBLE (4200 4950);
FORCEADD UNIVERSAL_GND..1
(4075 4050);
FORCEPROP 3 LASTPIN (4075 4100) SIG_NAME GND\g
J 0
(4085 4110);
DISPLAY 0.659574 (4085 4110);
PAINT MONO (4085 4110);
DISPLAY INVISIBLE (4085 4110);
FORCEPROP 1 LAST PATH I233
J 0
(4150 4050);
DISPLAY 0.872340 (4150 4050);
PAINT AQUA (4150 4050);
DISPLAY INVISIBLE (4150 4050);
FORCEPROP 2 LAST CDS_LIB logical_power
J 0
(4075 4050);
DISPLAY INVISIBLE (4075 4050);
FORCEPROP 1 LAST HDL_POWER GND
J 1
(4100 3975);
DISPLAY 0.872340 (4100 3975);
PAINT GREEN (4100 3975);
DISPLAY INVISIBLE (4100 3975);
FORCEADD CONN1_10165288101LF..1
(4150 3250);
FORCEPROP 1 LAST PART_NUMBER DFHS03FR030
J 0
(4106 3509);
DISPLAY 0.723404 (4106 3509);
PAINT GREEN (4106 3509);
DISPLAY INVISIBLE (4106 3509);
FORCEPROP 2 LAST VALUE CONN1_10165288-101LF
J 0
(4125 3700);
DISPLAY 1.021277 (4125 3700);
FORCEPROP 1 LAST MATERIAL IO
J 0
(4106 3382);
DISPLAY 0.723404 (4106 3382);
PAINT GREEN (4106 3382);
FORCEPROP 2 LAST PART_TYPE THLF
J 0
(4125 3750);
DISPLAY 1.021277 (4125 3750);
FORCEPROP 1 LAST $LOCATION J122
J 0
(4106 3656);
DISPLAY 0.723404 (4106 3656);
PAINT GREEN (4106 3656);
FORCEPROP 0 LASTPIN (4350 3225) $PN SCR_H1
J 0
(4360 3235);
DISPLAY 0.680851 (4360 3235);
PAINT MONO (4360 3235);
FORCEPROP 2 LAST CDS_LIB pure_quanta
J 0
(4150 3250);
DISPLAY INVISIBLE (4150 3250);
FORCEPROP 1 LAST PATH I238
J 0
(4150 3250);
DISPLAY 0.723404 (4150 3250);
PAINT GREEN (4150 3250);
DISPLAY INVISIBLE (4150 3250);
FORCEPROP 1 LAST NEEDS_NO_SIZE TRUE
J 0
(4150 3250);
DISPLAY 0.723404 (4150 3250);
PAINT GREEN (4150 3250);
DISPLAY INVISIBLE (4150 3250);
FORCEPROP 1 LAST CDS_LMAN_SYM_OUTLINE -50,125,50,-125
J 0
(4150 3250);
DISPLAY 0.468085 (4150 3250);
PAINT GREEN (4150 3250);
DISPLAY INVISIBLE (4150 3250);
FORCEPROP 0 LAST CDS_LOCATION J122
J 0
(4125 3800);
DISPLAY 1.021277 (4125 3800);
DISPLAY INVISIBLE (4125 3800);
FORCEPROP 0 LAST $SEC 1
J 0
(4125 3800);
DISPLAY 0.680851 (4125 3800);
PAINT MONO (4125 3800);
DISPLAY INVISIBLE (4125 3800);
FORCEPROP 0 LAST CDS_SEC 1
J 0
(4125 3800);
DISPLAY 1.021277 (4125 3800);
DISPLAY INVISIBLE (4125 3800);
FORCEADD CONN1_10165288101LF..1
(5150 3250);
FORCEPROP 1 LAST PART_NUMBER DFHS03FR030
J 0
(5106 3509);
DISPLAY 0.723404 (5106 3509);
PAINT GREEN (5106 3509);
DISPLAY INVISIBLE (5106 3509);
FORCEPROP 2 LAST VALUE CONN1_10165288-101LF
J 0
(5125 3700);
DISPLAY 1.021277 (5125 3700);
FORCEPROP 2 LAST PART_TYPE THLF
J 0
(5125 3750);
DISPLAY 1.021277 (5125 3750);
FORCEPROP 1 LAST MATERIAL IO
J 0
(5106 3382);
DISPLAY 0.723404 (5106 3382);
PAINT GREEN (5106 3382);
FORCEPROP 1 LAST $LOCATION J123
J 0
(5106 3656);
DISPLAY 0.723404 (5106 3656);
PAINT GREEN (5106 3656);
FORCEPROP 0 LASTPIN (5350 3225) $PN SCR_H1
J 0
(5360 3235);
DISPLAY 0.680851 (5360 3235);
PAINT MONO (5360 3235);
FORCEPROP 2 LAST CDS_LIB pure_quanta
J 0
(5150 3250);
DISPLAY INVISIBLE (5150 3250);
FORCEPROP 1 LAST PATH I239
J 0
(5150 3250);
DISPLAY 0.723404 (5150 3250);
PAINT GREEN (5150 3250);
DISPLAY INVISIBLE (5150 3250);
FORCEPROP 1 LAST CDS_LMAN_SYM_OUTLINE -50,125,50,-125
J 0
(5150 3250);
DISPLAY 0.468085 (5150 3250);
PAINT GREEN (5150 3250);
DISPLAY INVISIBLE (5150 3250);
FORCEPROP 1 LAST NEEDS_NO_SIZE TRUE
J 0
(5150 3250);
DISPLAY 0.723404 (5150 3250);
PAINT GREEN (5150 3250);
DISPLAY INVISIBLE (5150 3250);
FORCEPROP 0 LAST CDS_LOCATION J123
J 0
(5125 3800);
DISPLAY 1.021277 (5125 3800);
DISPLAY INVISIBLE (5125 3800);
FORCEPROP 0 LAST $SEC 1
J 0
(5125 3800);
DISPLAY 0.680851 (5125 3800);
PAINT MONO (5125 3800);
DISPLAY INVISIBLE (5125 3800);
FORCEPROP 0 LAST CDS_SEC 1
J 0
(5125 3800);
DISPLAY 1.021277 (5125 3800);
DISPLAY INVISIBLE (5125 3800);
FORCEADD UNIVERSAL_GND..1
(50 -925);
FORCEPROP 3 LASTPIN (50 -875) SIG_NAME GND\g
J 0
(60 -865);
DISPLAY 0.659574 (60 -865);
PAINT MONO (60 -865);
DISPLAY INVISIBLE (60 -865);
FORCEPROP 1 LAST PATH I243
J 0
(125 -925);
DISPLAY 0.872340 (125 -925);
PAINT AQUA (125 -925);
DISPLAY INVISIBLE (125 -925);
FORCEPROP 1 LAST HDL_POWER GND
J 1
(75 -1000);
DISPLAY 0.872340 (75 -1000);
PAINT GREEN (75 -1000);
DISPLAY INVISIBLE (75 -1000);
FORCEPROP 2 LAST CDS_LIB logical_power
J 0
(50 -925);
DISPLAY INVISIBLE (50 -925);
FORCEADD UNIVERSAL_GND..1
(-725 -925);
FORCEPROP 3 LASTPIN (-725 -875) SIG_NAME GND\g
J 0
(-715 -865);
DISPLAY 0.659574 (-715 -865);
PAINT MONO (-715 -865);
DISPLAY INVISIBLE (-715 -865);
FORCEPROP 1 LAST PATH I244
J 0
(-650 -925);
DISPLAY 0.872340 (-650 -925);
PAINT AQUA (-650 -925);
DISPLAY INVISIBLE (-650 -925);
FORCEPROP 2 LAST CDS_LIB logical_power
J 0
(-725 -925);
DISPLAY INVISIBLE (-725 -925);
FORCEPROP 1 LAST HDL_POWER GND
J 1
(-700 -1000);
DISPLAY 0.872340 (-700 -1000);
PAINT GREEN (-700 -1000);
DISPLAY INVISIBLE (-700 -1000);
FORCEADD UNIVERSAL_GND..1
(5125 1000);
FORCEPROP 3 LASTPIN (5125 1050) SIG_NAME GND\g
J 0
(5135 1060);
DISPLAY 0.659574 (5135 1060);
PAINT MONO (5135 1060);
DISPLAY INVISIBLE (5135 1060);
FORCEPROP 2 LAST CDS_LIB logical_power
J 0
(5125 1000);
DISPLAY INVISIBLE (5125 1000);
FORCEPROP 1 LAST PATH I245
J 0
(5200 1000);
DISPLAY 0.872340 (5200 1000);
PAINT AQUA (5200 1000);
DISPLAY INVISIBLE (5200 1000);
FORCEPROP 1 LAST HDL_POWER GND
J 1
(5150 925);
DISPLAY 0.872340 (5150 925);
PAINT GREEN (5150 925);
DISPLAY INVISIBLE (5150 925);
FORCEADD GND_HOLE..1
(-450 -525);
FORCEPROP 1 LAST PART_NUMBER TMP-QGND_HOLE12
J 0
(-600 -140);
DISPLAY 0.723404 (-600 -140);
PAINT GREEN (-600 -140);
DISPLAY INVISIBLE (-600 -140);
FORCEPROP 1 LAST MATERIAL EMPTY
J 0
(-600 -195);
DISPLAY 0.723404 (-600 -195);
PAINT GREEN (-600 -195);
FORCEPROP 2 LAST PACK_TYPE TH
J 0
(-600 -50);
DISPLAY 1.021277 (-600 -50);
FORCEPROP 1 LAST LOCATION H113
J 0
(-600 -100);
DISPLAY 0.723404 (-600 -100);
PAINT GREEN (-600 -100);
FORCEPROP 0 LASTPIN (-250 -525) $PN 2
J 0
(-240 -515);
DISPLAY 0.680851 (-240 -515);
PAINT MONO (-240 -515);
FORCEPROP 0 LASTPIN (-250 -425) $PN 3
J 0
(-240 -415);
DISPLAY 0.680851 (-240 -415);
PAINT MONO (-240 -415);
FORCEPROP 0 LASTPIN (-450 -325) $PN 4
R 1
J 0
(-460 -315);
DISPLAY 0.680851 (-460 -315);
PAINT MONO (-460 -315);
FORCEPROP 0 LASTPIN (-650 -425) $PN 5
J 2
(-660 -415);
DISPLAY 0.680851 (-660 -415);
PAINT MONO (-660 -415);
FORCEPROP 0 LASTPIN (-650 -525) $PN 6
J 2
(-660 -515);
DISPLAY 0.680851 (-660 -515);
PAINT MONO (-660 -515);
FORCEPROP 0 LASTPIN (-550 -725) $PN 7
R 1
J 2
(-560 -735);
DISPLAY 0.680851 (-560 -735);
PAINT MONO (-560 -735);
FORCEPROP 0 LASTPIN (-450 -725) $PN 8
R 1
J 2
(-460 -735);
DISPLAY 0.680851 (-460 -735);
PAINT MONO (-460 -735);
FORCEPROP 0 LASTPIN (-350 -725) $PN 9
R 1
J 2
(-360 -735);
DISPLAY 0.680851 (-360 -735);
PAINT MONO (-360 -735);
FORCEPROP 2 LAST CDS_LIB pure_quanta
J 0
(-450 -525);
DISPLAY INVISIBLE (-450 -525);
FORCEPROP 1 LAST PATH I247
J 0
(-350 -215);
DISPLAY 0.723404 (-350 -215);
PAINT GREEN (-350 -215);
DISPLAY INVISIBLE (-350 -215);
FORCEPROP 1 LAST NEEDS_NO_SIZE TRUE
J 0
(-450 -525);
DISPLAY 0.468085 (-450 -525);
PAINT GREEN (-450 -525);
DISPLAY INVISIBLE (-450 -525);
FORCEPROP 0 LAST $SEC 1
J 0
(-600 0);
DISPLAY 0.680851 (-600 0);
PAINT MONO (-600 0);
DISPLAY INVISIBLE (-600 0);
FORCEPROP 0 LAST CDS_SEC 1
J 0
(-600 0);
DISPLAY 1.021277 (-600 0);
DISPLAY INVISIBLE (-600 0);
FORCEADD GND_HOLE..1
(325 -525);
FORCEPROP 1 LAST PART_NUMBER TMP-QGND_HOLE12
J 0
(175 -140);
DISPLAY 0.723404 (175 -140);
PAINT GREEN (175 -140);
DISPLAY INVISIBLE (175 -140);
FORCEPROP 2 LAST PACK_TYPE TH
J 0
(175 -50);
DISPLAY 1.021277 (175 -50);
FORCEPROP 1 LAST MATERIAL EMPTY
J 0
(175 -195);
DISPLAY 0.723404 (175 -195);
PAINT GREEN (175 -195);
FORCEPROP 1 LAST LOCATION H114
J 0
(175 -100);
DISPLAY 0.723404 (175 -100);
PAINT GREEN (175 -100);
FORCEPROP 0 LASTPIN (525 -525) $PN 2
J 0
(535 -515);
DISPLAY 0.680851 (535 -515);
PAINT MONO (535 -515);
FORCEPROP 0 LASTPIN (525 -425) $PN 3
J 0
(535 -415);
DISPLAY 0.680851 (535 -415);
PAINT MONO (535 -415);
FORCEPROP 0 LASTPIN (325 -325) $PN 4
R 1
J 0
(315 -315);
DISPLAY 0.680851 (315 -315);
PAINT MONO (315 -315);
FORCEPROP 0 LASTPIN (125 -425) $PN 5
J 2
(115 -415);
DISPLAY 0.680851 (115 -415);
PAINT MONO (115 -415);
FORCEPROP 0 LASTPIN (125 -525) $PN 6
J 2
(115 -515);
DISPLAY 0.680851 (115 -515);
PAINT MONO (115 -515);
FORCEPROP 0 LASTPIN (225 -725) $PN 7
R 1
J 2
(215 -735);
DISPLAY 0.680851 (215 -735);
PAINT MONO (215 -735);
FORCEPROP 0 LASTPIN (325 -725) $PN 8
R 1
J 2
(315 -735);
DISPLAY 0.680851 (315 -735);
PAINT MONO (315 -735);
FORCEPROP 0 LASTPIN (425 -725) $PN 9
R 1
J 2
(415 -735);
DISPLAY 0.680851 (415 -735);
PAINT MONO (415 -735);
FORCEPROP 1 LAST NEEDS_NO_SIZE TRUE
J 0
(325 -525);
DISPLAY 0.468085 (325 -525);
PAINT GREEN (325 -525);
DISPLAY INVISIBLE (325 -525);
FORCEPROP 1 LAST PATH I248
J 0
(425 -215);
DISPLAY 0.723404 (425 -215);
PAINT GREEN (425 -215);
DISPLAY INVISIBLE (425 -215);
FORCEPROP 2 LAST CDS_LIB pure_quanta
J 0
(325 -525);
DISPLAY INVISIBLE (325 -525);
FORCEPROP 0 LAST $SEC 1
J 0
(175 0);
DISPLAY 0.680851 (175 0);
PAINT MONO (175 0);
DISPLAY INVISIBLE (175 0);
FORCEPROP 0 LAST CDS_SEC 1
J 0
(175 0);
DISPLAY 1.021277 (175 0);
DISPLAY INVISIBLE (175 0);
FORCEADD HOLE..1
(5400 1150);
FORCEPROP 1 LAST PART_NUMBER HOLE1195
J 0
(5275 1330);
DISPLAY 0.723404 (5275 1330);
PAINT GREEN (5275 1330);
DISPLAY INVISIBLE (5275 1330);
FORCEPROP 2 LAST PACK_TYPE TH
J 0
(5275 1425);
DISPLAY 1.021277 (5275 1425);
FORCEPROP 1 LAST MATERIAL EMPTY
J 0
(5275 1285);
DISPLAY 0.723404 (5275 1285);
PAINT GREEN (5275 1285);
FORCEPROP 1 LAST LOCATION H129
J 0
(5275 1385);
DISPLAY 0.723404 (5275 1385);
PAINT GREEN (5275 1385);
FORCEPROP 0 LASTPIN (5200 1175) $PN 1
J 2
(5190 1185);
DISPLAY 0.680851 (5190 1185);
PAINT MONO (5190 1185);
FORCEPROP 1 LAST NEEDS_NO_SIZE TRUE
J 0
(5400 1150);
DISPLAY 0.468085 (5400 1150);
PAINT GREEN (5400 1150);
DISPLAY INVISIBLE (5400 1150);
FORCEPROP 1 LAST PATH I249
J 0
(5450 1280);
DISPLAY 0.723404 (5450 1280);
PAINT GREEN (5450 1280);
DISPLAY INVISIBLE (5450 1280);
FORCEPROP 2 LAST CDS_LIB pure_quanta
J 0
(5400 1150);
DISPLAY INVISIBLE (5400 1150);
FORCEPROP 0 LAST $SEC 1
J 0
(5275 1475);
DISPLAY 0.680851 (5275 1475);
PAINT MONO (5275 1475);
DISPLAY INVISIBLE (5275 1475);
FORCEPROP 0 LAST CDS_SEC 1
J 0
(5275 1475);
DISPLAY 1.021277 (5275 1475);
DISPLAY INVISIBLE (5275 1475);
FORCEADD HOLE..1
(5275 4050);
FORCEPROP 1 LAST PART_NUMBER HOLE372
J 0
(5150 4230);
DISPLAY 0.723404 (5150 4230);
PAINT GREEN (5150 4230);
DISPLAY INVISIBLE (5150 4230);
FORCEPROP 1 LAST MATERIAL EMPTY
J 0
(5150 4185);
DISPLAY 0.723404 (5150 4185);
PAINT GREEN (5150 4185);
FORCEPROP 2 LAST PACK_TYPE TH
J 0
(5150 4325);
DISPLAY 1.021277 (5150 4325);
FORCEPROP 1 LAST LOCATION H90
J 0
(5150 4285);
DISPLAY 0.723404 (5150 4285);
PAINT GREEN (5150 4285);
FORCEPROP 0 LASTPIN (5075 4075) $PN 1
J 2
(5065 4085);
DISPLAY 0.680851 (5065 4085);
PAINT MONO (5065 4085);
FORCEPROP 2 LAST CDS_LIB pure_quanta
J 0
(5275 4050);
DISPLAY INVISIBLE (5275 4050);
FORCEPROP 1 LAST PATH I254
J 0
(5325 4180);
DISPLAY 0.723404 (5325 4180);
PAINT GREEN (5325 4180);
DISPLAY INVISIBLE (5325 4180);
FORCEPROP 1 LAST NEEDS_NO_SIZE TRUE
J 0
(5275 4050);
DISPLAY 0.468085 (5275 4050);
PAINT GREEN (5275 4050);
DISPLAY INVISIBLE (5275 4050);
FORCEPROP 0 LAST $SEC 1
J 0
(5150 4375);
DISPLAY 0.680851 (5150 4375);
PAINT MONO (5150 4375);
DISPLAY INVISIBLE (5150 4375);
FORCEPROP 0 LAST CDS_SEC 1
J 0
(5150 4375);
DISPLAY 1.021277 (5150 4375);
DISPLAY INVISIBLE (5150 4375);
FORCEADD HOLE..1
(4375 2150);
FORCEPROP 1 LAST PART_NUMBER HOLE1248
J 0
(4250 2330);
DISPLAY 0.723404 (4250 2330);
PAINT GREEN (4250 2330);
DISPLAY INVISIBLE (4250 2330);
FORCEPROP 1 LAST MATERIAL EMPTY
J 0
(4250 2285);
DISPLAY 0.723404 (4250 2285);
PAINT GREEN (4250 2285);
FORCEPROP 2 LAST PACK_TYPE TH
J 0
(4250 2425);
DISPLAY 1.021277 (4250 2425);
FORCEPROP 1 LAST $LOCATION H32
J 0
(4250 2385);
DISPLAY 0.723404 (4250 2385);
PAINT GREEN (4250 2385);
FORCEPROP 0 LASTPIN (4175 2175) $PN 1
J 2
(4165 2185);
DISPLAY 0.680851 (4165 2185);
PAINT MONO (4165 2185);
FORCEPROP 1 LAST NEEDS_NO_SIZE TRUE
J 0
(4375 2150);
DISPLAY 0.468085 (4375 2150);
PAINT GREEN (4375 2150);
DISPLAY INVISIBLE (4375 2150);
FORCEPROP 2 LAST CDS_LIB pure_quanta
J 0
(4375 2150);
DISPLAY INVISIBLE (4375 2150);
FORCEPROP 1 LAST PATH I54
J 0
(4425 2280);
DISPLAY 0.723404 (4425 2280);
PAINT GREEN (4425 2280);
DISPLAY INVISIBLE (4425 2280);
FORCEPROP 2 LAST CDS_LOCATION H32
J 0
(4250 2475);
DISPLAY 1.021277 (4250 2475);
DISPLAY INVISIBLE (4250 2475);
FORCEPROP 0 LAST $SEC 1
J 0
(4250 2475);
DISPLAY 0.680851 (4250 2475);
PAINT MONO (4250 2475);
DISPLAY INVISIBLE (4250 2475);
FORCEPROP 2 LAST CDS_SEC 1
J 0
(4250 2475);
DISPLAY 1.021277 (4250 2475);
DISPLAY INVISIBLE (4250 2475);
FORCEADD UNIVERSAL_GND..1
(4100 2000);
FORCEPROP 3 LASTPIN (4100 2050) SIG_NAME GND\g
J 0
(4110 2060);
DISPLAY 0.659574 (4110 2060);
PAINT MONO (4110 2060);
DISPLAY INVISIBLE (4110 2060);
FORCEPROP 1 LAST HDL_POWER GND
J 1
(4125 1925);
DISPLAY 0.872340 (4125 1925);
PAINT GREEN (4125 1925);
DISPLAY INVISIBLE (4125 1925);
FORCEPROP 2 LAST CDS_LIB logical_power
J 0
(4100 2000);
DISPLAY INVISIBLE (4100 2000);
FORCEPROP 1 LAST PATH I55
J 0
(4175 2000);
DISPLAY 0.872340 (4175 2000);
PAINT AQUA (4175 2000);
DISPLAY INVISIBLE (4175 2000);
FORCEADD HOLE..1
(3875 2150);
FORCEPROP 1 LAST PART_NUMBER HOLE1248
J 0
(3750 2330);
DISPLAY 0.723404 (3750 2330);
PAINT GREEN (3750 2330);
DISPLAY INVISIBLE (3750 2330);
FORCEPROP 2 LAST PACK_TYPE TH
J 0
(3750 2425);
DISPLAY 1.021277 (3750 2425);
FORCEPROP 1 LAST MATERIAL EMPTY
J 0
(3750 2285);
DISPLAY 0.723404 (3750 2285);
PAINT GREEN (3750 2285);
FORCEPROP 1 LAST $LOCATION H31
J 0
(3750 2385);
DISPLAY 0.723404 (3750 2385);
PAINT GREEN (3750 2385);
FORCEPROP 0 LASTPIN (3675 2175) $PN 1
J 2
(3665 2185);
DISPLAY 0.680851 (3665 2185);
PAINT MONO (3665 2185);
FORCEPROP 1 LAST NEEDS_NO_SIZE TRUE
J 0
(3875 2150);
DISPLAY 0.468085 (3875 2150);
PAINT GREEN (3875 2150);
DISPLAY INVISIBLE (3875 2150);
FORCEPROP 2 LAST CDS_LIB pure_quanta
J 0
(3875 2150);
DISPLAY INVISIBLE (3875 2150);
FORCEPROP 1 LAST PATH I56
J 0
(3925 2280);
DISPLAY 0.723404 (3925 2280);
PAINT GREEN (3925 2280);
DISPLAY INVISIBLE (3925 2280);
FORCEPROP 2 LAST CDS_LOCATION H31
J 0
(3750 2475);
DISPLAY 1.021277 (3750 2475);
DISPLAY INVISIBLE (3750 2475);
FORCEPROP 0 LAST $SEC 1
J 0
(3750 2475);
DISPLAY 0.680851 (3750 2475);
PAINT MONO (3750 2475);
DISPLAY INVISIBLE (3750 2475);
FORCEPROP 2 LAST CDS_SEC 1
J 0
(3750 2475);
DISPLAY 1.021277 (3750 2475);
DISPLAY INVISIBLE (3750 2475);
FORCEADD HOLE..1
(3050 2225);
FORCEPROP 1 LAST PART_NUMBER HOLE1247
J 0
(2925 2405);
DISPLAY 0.723404 (2925 2405);
PAINT GREEN (2925 2405);
DISPLAY INVISIBLE (2925 2405);
FORCEPROP 1 LAST MATERIAL EMPTY
J 0
(2925 2360);
DISPLAY 0.723404 (2925 2360);
PAINT GREEN (2925 2360);
FORCEPROP 2 LAST PACK_TYPE TH
J 0
(2925 2500);
DISPLAY 1.021277 (2925 2500);
FORCEPROP 1 LAST $LOCATION H75
J 0
(2925 2460);
DISPLAY 0.723404 (2925 2460);
PAINT GREEN (2925 2460);
FORCEPROP 0 LASTPIN (2850 2250) $PN 1
J 2
(2840 2260);
DISPLAY 0.680851 (2840 2260);
PAINT MONO (2840 2260);
FORCEPROP 1 LAST PATH I57
J 0
(3100 2355);
DISPLAY 0.723404 (3100 2355);
PAINT GREEN (3100 2355);
DISPLAY INVISIBLE (3100 2355);
FORCEPROP 1 LAST NEEDS_NO_SIZE TRUE
J 0
(3050 2225);
DISPLAY 0.468085 (3050 2225);
PAINT GREEN (3050 2225);
DISPLAY INVISIBLE (3050 2225);
FORCEPROP 2 LAST CDS_LIB pure_quanta
J 0
(3050 2225);
DISPLAY INVISIBLE (3050 2225);
FORCEPROP 0 LAST CDS_LOCATION H75
J 0
(2925 2550);
DISPLAY 1.021277 (2925 2550);
DISPLAY INVISIBLE (2925 2550);
FORCEPROP 0 LAST $SEC 1
J 0
(2925 2550);
DISPLAY 0.680851 (2925 2550);
PAINT MONO (2925 2550);
DISPLAY INVISIBLE (2925 2550);
FORCEPROP 0 LAST CDS_SEC 1
J 0
(2925 2550);
DISPLAY 1.021277 (2925 2550);
DISPLAY INVISIBLE (2925 2550);
FORCEADD HOLE..1
(2550 2225);
FORCEPROP 1 LAST PART_NUMBER HOLE1247
J 0
(2425 2405);
DISPLAY 0.723404 (2425 2405);
PAINT GREEN (2425 2405);
DISPLAY INVISIBLE (2425 2405);
FORCEPROP 1 LAST MATERIAL EMPTY
J 0
(2425 2360);
DISPLAY 0.723404 (2425 2360);
PAINT GREEN (2425 2360);
FORCEPROP 2 LAST PACK_TYPE TH
J 0
(2425 2500);
DISPLAY 1.021277 (2425 2500);
FORCEPROP 1 LAST $LOCATION H74
J 0
(2425 2460);
DISPLAY 0.723404 (2425 2460);
PAINT GREEN (2425 2460);
FORCEPROP 0 LASTPIN (2350 2250) $PN 1
J 2
(2340 2260);
DISPLAY 0.680851 (2340 2260);
PAINT MONO (2340 2260);
FORCEPROP 1 LAST PATH I58
J 0
(2600 2355);
DISPLAY 0.723404 (2600 2355);
PAINT GREEN (2600 2355);
DISPLAY INVISIBLE (2600 2355);
FORCEPROP 1 LAST NEEDS_NO_SIZE TRUE
J 0
(2550 2225);
DISPLAY 0.468085 (2550 2225);
PAINT GREEN (2550 2225);
DISPLAY INVISIBLE (2550 2225);
FORCEPROP 2 LAST CDS_LIB pure_quanta
J 0
(2550 2225);
DISPLAY INVISIBLE (2550 2225);
FORCEPROP 0 LAST CDS_LOCATION H74
J 0
(2425 2550);
DISPLAY 1.021277 (2425 2550);
DISPLAY INVISIBLE (2425 2550);
FORCEPROP 0 LAST $SEC 1
J 0
(2425 2550);
DISPLAY 0.680851 (2425 2550);
PAINT MONO (2425 2550);
DISPLAY INVISIBLE (2425 2550);
FORCEPROP 0 LAST CDS_SEC 1
J 0
(2425 2550);
DISPLAY 1.021277 (2425 2550);
DISPLAY INVISIBLE (2425 2550);
FORCEADD UNIVERSAL_GND..1
(3600 2000);
FORCEPROP 3 LASTPIN (3600 2050) SIG_NAME GND\g
J 0
(3610 2060);
DISPLAY 0.659574 (3610 2060);
PAINT MONO (3610 2060);
DISPLAY INVISIBLE (3610 2060);
FORCEPROP 1 LAST PATH I59
J 0
(3675 2000);
DISPLAY 0.872340 (3675 2000);
PAINT AQUA (3675 2000);
DISPLAY INVISIBLE (3675 2000);
FORCEPROP 2 LAST CDS_LIB logical_power
J 0
(3600 2000);
DISPLAY INVISIBLE (3600 2000);
FORCEPROP 1 LAST HDL_POWER GND
J 1
(3625 1925);
DISPLAY 0.872340 (3625 1925);
PAINT GREEN (3625 1925);
DISPLAY INVISIBLE (3625 1925);
FORCEADD HOLE..1
(-1525 750);
FORCEPROP 1 LAST PART_NUMBER HOLE1079
J 0
(-1650 930);
DISPLAY 0.723404 (-1650 930);
PAINT GREEN (-1650 930);
DISPLAY INVISIBLE (-1650 930);
FORCEPROP 2 LAST PACK_TYPE TH
J 0
(-1650 1025);
DISPLAY 1.021277 (-1650 1025);
FORCEPROP 1 LAST MATERIAL EMPTY
J 0
(-1650 885);
DISPLAY 0.723404 (-1650 885);
PAINT GREEN (-1650 885);
FORCEPROP 1 LAST $LOCATION H20
J 0
(-1650 985);
DISPLAY 0.723404 (-1650 985);
PAINT GREEN (-1650 985);
FORCEPROP 2 LASTPIN (-1725 775) $PN 1
J 2
(-1735 785);
DISPLAY 0.808511 (-1735 785);
FORCEPROP 2 LAST CDS_LIB pure_quanta
J 0
(-1525 750);
PAINT MONO (-1525 750);
DISPLAY INVISIBLE (-1525 750);
FORCEPROP 1 LAST NEEDS_NO_SIZE TRUE
J 0
(-1525 750);
DISPLAY 0.468085 (-1525 750);
PAINT GREEN (-1525 750);
DISPLAY INVISIBLE (-1525 750);
FORCEPROP 1 LAST PATH I60
J 0
(-1475 880);
DISPLAY 0.723404 (-1475 880);
PAINT GREEN (-1475 880);
DISPLAY INVISIBLE (-1475 880);
FORCEPROP 2 LAST CDS_LOCATION H20
J 0
(-1650 1075);
DISPLAY 1.021277 (-1650 1075);
DISPLAY INVISIBLE (-1650 1075);
FORCEPROP 2 LAST $SEC 1
J 0
(-1650 1075);
DISPLAY 0.680851 (-1650 1075);
PAINT MONO (-1650 1075);
DISPLAY INVISIBLE (-1650 1075);
FORCEPROP 2 LAST CDS_SEC 1
J 0
(-1650 1075);
DISPLAY 1.021277 (-1650 1075);
DISPLAY INVISIBLE (-1650 1075);
FORCEADD HOLE..1
(-2025 750);
FORCEPROP 1 LAST PART_NUMBER HOLE1079
J 0
(-2150 930);
DISPLAY 0.723404 (-2150 930);
PAINT GREEN (-2150 930);
DISPLAY INVISIBLE (-2150 930);
FORCEPROP 2 LAST PACK_TYPE TH
J 0
(-2150 1025);
DISPLAY 1.021277 (-2150 1025);
FORCEPROP 1 LAST MATERIAL EMPTY
J 0
(-2150 885);
DISPLAY 0.723404 (-2150 885);
PAINT GREEN (-2150 885);
FORCEPROP 1 LAST $LOCATION H18
J 0
(-2150 985);
DISPLAY 0.723404 (-2150 985);
PAINT GREEN (-2150 985);
FORCEPROP 2 LASTPIN (-2225 775) $PN 1
J 2
(-2235 785);
DISPLAY 0.808511 (-2235 785);
FORCEPROP 2 LAST CDS_LIB pure_quanta
J 0
(-2025 750);
PAINT MONO (-2025 750);
DISPLAY INVISIBLE (-2025 750);
FORCEPROP 1 LAST NEEDS_NO_SIZE TRUE
J 0
(-2025 750);
DISPLAY 0.468085 (-2025 750);
PAINT GREEN (-2025 750);
DISPLAY INVISIBLE (-2025 750);
FORCEPROP 1 LAST PATH I61
J 0
(-1975 880);
DISPLAY 0.723404 (-1975 880);
PAINT GREEN (-1975 880);
DISPLAY INVISIBLE (-1975 880);
FORCEPROP 2 LAST CDS_LOCATION H18
J 0
(-2150 1075);
DISPLAY 1.021277 (-2150 1075);
DISPLAY INVISIBLE (-2150 1075);
FORCEPROP 2 LAST $SEC 1
J 0
(-2150 1075);
DISPLAY 0.680851 (-2150 1075);
PAINT MONO (-2150 1075);
DISPLAY INVISIBLE (-2150 1075);
FORCEPROP 2 LAST CDS_SEC 1
J 0
(-2150 1075);
DISPLAY 1.021277 (-2150 1075);
DISPLAY INVISIBLE (-2150 1075);
FORCEADD HOLE..1
(-2525 750);
FORCEPROP 1 LAST PART_NUMBER HOLE1079
J 0
(-2650 930);
DISPLAY 0.723404 (-2650 930);
PAINT GREEN (-2650 930);
DISPLAY INVISIBLE (-2650 930);
FORCEPROP 2 LAST PACK_TYPE TH
J 0
(-2650 1025);
DISPLAY 1.021277 (-2650 1025);
FORCEPROP 1 LAST MATERIAL EMPTY
J 0
(-2650 885);
DISPLAY 0.723404 (-2650 885);
PAINT GREEN (-2650 885);
FORCEPROP 1 LAST $LOCATION H16
J 0
(-2650 985);
DISPLAY 0.723404 (-2650 985);
PAINT GREEN (-2650 985);
FORCEPROP 2 LASTPIN (-2725 775) $PN 1
J 2
(-2735 785);
DISPLAY 0.808511 (-2735 785);
FORCEPROP 2 LAST CDS_LIB pure_quanta
J 0
(-2525 750);
PAINT MONO (-2525 750);
DISPLAY INVISIBLE (-2525 750);
FORCEPROP 1 LAST NEEDS_NO_SIZE TRUE
J 0
(-2525 750);
DISPLAY 0.468085 (-2525 750);
PAINT GREEN (-2525 750);
DISPLAY INVISIBLE (-2525 750);
FORCEPROP 1 LAST PATH I63
J 0
(-2475 880);
DISPLAY 0.723404 (-2475 880);
PAINT GREEN (-2475 880);
DISPLAY INVISIBLE (-2475 880);
FORCEPROP 2 LAST CDS_LOCATION H16
J 0
(-2650 1075);
DISPLAY 1.021277 (-2650 1075);
DISPLAY INVISIBLE (-2650 1075);
FORCEPROP 2 LAST $SEC 1
J 0
(-2650 1075);
DISPLAY 0.680851 (-2650 1075);
PAINT MONO (-2650 1075);
DISPLAY INVISIBLE (-2650 1075);
FORCEPROP 2 LAST CDS_SEC 1
J 0
(-2650 1075);
DISPLAY 1.021277 (-2650 1075);
DISPLAY INVISIBLE (-2650 1075);
FORCEADD HOLE..1
(25 1250);
FORCEPROP 1 LAST PART_NUMBER HOLE1079
J 0
(-100 1430);
DISPLAY 0.723404 (-100 1430);
PAINT GREEN (-100 1430);
DISPLAY INVISIBLE (-100 1430);
FORCEPROP 1 LAST MATERIAL EMPTY
J 0
(-100 1385);
DISPLAY 0.723404 (-100 1385);
PAINT GREEN (-100 1385);
FORCEPROP 2 LAST PACK_TYPE TH
J 0
(-100 1525);
DISPLAY 1.021277 (-100 1525);
FORCEPROP 1 LAST $LOCATION H25
J 0
(-100 1485);
DISPLAY 0.723404 (-100 1485);
PAINT GREEN (-100 1485);
FORCEPROP 2 LASTPIN (-175 1275) $PN 1
J 2
(-185 1285);
DISPLAY 0.808511 (-185 1285);
FORCEPROP 1 LAST PATH I64
J 0
(75 1380);
DISPLAY 0.723404 (75 1380);
PAINT GREEN (75 1380);
DISPLAY INVISIBLE (75 1380);
FORCEPROP 1 LAST NEEDS_NO_SIZE TRUE
J 0
(25 1250);
DISPLAY 0.468085 (25 1250);
PAINT GREEN (25 1250);
DISPLAY INVISIBLE (25 1250);
FORCEPROP 2 LAST CDS_LIB pure_quanta
J 0
(25 1250);
PAINT MONO (25 1250);
DISPLAY INVISIBLE (25 1250);
FORCEPROP 2 LAST CDS_LOCATION H25
J 0
(-100 1575);
DISPLAY 1.021277 (-100 1575);
DISPLAY INVISIBLE (-100 1575);
FORCEPROP 2 LAST $SEC 1
J 0
(-100 1575);
DISPLAY 0.680851 (-100 1575);
PAINT MONO (-100 1575);
DISPLAY INVISIBLE (-100 1575);
FORCEPROP 2 LAST CDS_SEC 1
J 0
(-100 1575);
DISPLAY 1.021277 (-100 1575);
DISPLAY INVISIBLE (-100 1575);
FORCEADD HOLE..1
(1800 2275);
FORCEPROP 1 LAST PART_NUMBER DUMMY50
J 0
(1675 2455);
DISPLAY 0.723404 (1675 2455);
PAINT GREEN (1675 2455);
DISPLAY INVISIBLE (1675 2455);
FORCEPROP 2 LAST PACK_TYPE TH
J 0
(1675 2550);
DISPLAY 1.021277 (1675 2550);
FORCEPROP 1 LAST MATERIAL EMPTY
J 0
(1675 2410);
DISPLAY 0.723404 (1675 2410);
PAINT GREEN (1675 2410);
FORCEPROP 1 LAST $LOCATION H30
J 0
(1675 2510);
DISPLAY 0.723404 (1675 2510);
PAINT GREEN (1675 2510);
FORCEPROP 2 LASTPIN (1600 2300) $PN 1
J 2
(1590 2310);
DISPLAY 0.808511 (1590 2310);
FORCEPROP 1 LAST PATH I7
J 0
(1850 2405);
DISPLAY 0.723404 (1850 2405);
PAINT GREEN (1850 2405);
DISPLAY INVISIBLE (1850 2405);
FORCEPROP 1 LAST NEEDS_NO_SIZE TRUE
J 0
(1800 2275);
DISPLAY 0.468085 (1800 2275);
PAINT GREEN (1800 2275);
DISPLAY INVISIBLE (1800 2275);
FORCEPROP 2 LAST CDS_LIB pure_quanta
J 0
(1800 2275);
PAINT MONO (1800 2275);
DISPLAY INVISIBLE (1800 2275);
FORCEPROP 2 LAST CDS_LOCATION H30
J 0
(1675 2600);
DISPLAY 1.021277 (1675 2600);
DISPLAY INVISIBLE (1675 2600);
FORCEPROP 2 LAST $SEC 1
J 0
(1675 2600);
DISPLAY 0.680851 (1675 2600);
PAINT MONO (1675 2600);
DISPLAY INVISIBLE (1675 2600);
FORCEPROP 2 LAST CDS_SEC 1
J 0
(1675 2600);
DISPLAY 1.021277 (1675 2600);
DISPLAY INVISIBLE (1675 2600);
FORCEADD HOLE..1
(-475 1250);
FORCEPROP 1 LAST PART_NUMBER HOLE1079
J 0
(-600 1430);
DISPLAY 0.723404 (-600 1430);
PAINT GREEN (-600 1430);
DISPLAY INVISIBLE (-600 1430);
FORCEPROP 2 LAST PACK_TYPE TH
J 0
(-600 1525);
DISPLAY 1.021277 (-600 1525);
FORCEPROP 1 LAST MATERIAL EMPTY
J 0
(-600 1385);
DISPLAY 0.723404 (-600 1385);
PAINT GREEN (-600 1385);
FORCEPROP 1 LAST $LOCATION H23
J 0
(-600 1485);
DISPLAY 0.723404 (-600 1485);
PAINT GREEN (-600 1485);
FORCEPROP 2 LASTPIN (-675 1275) $PN 1
J 2
(-685 1285);
DISPLAY 0.808511 (-685 1285);
FORCEPROP 1 LAST PATH I72
J 0
(-425 1380);
DISPLAY 0.723404 (-425 1380);
PAINT GREEN (-425 1380);
DISPLAY INVISIBLE (-425 1380);
FORCEPROP 1 LAST NEEDS_NO_SIZE TRUE
J 0
(-475 1250);
DISPLAY 0.468085 (-475 1250);
PAINT GREEN (-475 1250);
DISPLAY INVISIBLE (-475 1250);
FORCEPROP 2 LAST CDS_LIB pure_quanta
J 0
(-475 1250);
PAINT MONO (-475 1250);
DISPLAY INVISIBLE (-475 1250);
FORCEPROP 2 LAST CDS_LOCATION H23
J 0
(-600 1575);
DISPLAY 1.021277 (-600 1575);
DISPLAY INVISIBLE (-600 1575);
FORCEPROP 2 LAST $SEC 1
J 0
(-600 1575);
DISPLAY 0.680851 (-600 1575);
PAINT MONO (-600 1575);
DISPLAY INVISIBLE (-600 1575);
FORCEPROP 2 LAST CDS_SEC 1
J 0
(-600 1575);
DISPLAY 1.021277 (-600 1575);
DISPLAY INVISIBLE (-600 1575);
FORCEADD HOLE..1
(-1000 1250);
FORCEPROP 1 LAST PART_NUMBER HOLE1079
J 0
(-1125 1430);
DISPLAY 0.723404 (-1125 1430);
PAINT GREEN (-1125 1430);
DISPLAY INVISIBLE (-1125 1430);
FORCEPROP 1 LAST MATERIAL EMPTY
J 0
(-1125 1385);
DISPLAY 0.723404 (-1125 1385);
PAINT GREEN (-1125 1385);
FORCEPROP 2 LAST PACK_TYPE TH
J 0
(-1125 1525);
DISPLAY 1.021277 (-1125 1525);
FORCEPROP 1 LAST $LOCATION H21
J 0
(-1125 1485);
DISPLAY 0.723404 (-1125 1485);
PAINT GREEN (-1125 1485);
FORCEPROP 2 LASTPIN (-1200 1275) $PN 1
J 2
(-1210 1285);
DISPLAY 0.808511 (-1210 1285);
FORCEPROP 1 LAST PATH I73
J 0
(-950 1380);
DISPLAY 0.723404 (-950 1380);
PAINT GREEN (-950 1380);
DISPLAY INVISIBLE (-950 1380);
FORCEPROP 1 LAST NEEDS_NO_SIZE TRUE
J 0
(-1000 1250);
DISPLAY 0.468085 (-1000 1250);
PAINT GREEN (-1000 1250);
DISPLAY INVISIBLE (-1000 1250);
FORCEPROP 2 LAST CDS_LIB pure_quanta
J 0
(-1000 1250);
PAINT MONO (-1000 1250);
DISPLAY INVISIBLE (-1000 1250);
FORCEPROP 2 LAST CDS_LOCATION H21
J 0
(-1125 1575);
DISPLAY 1.021277 (-1125 1575);
DISPLAY INVISIBLE (-1125 1575);
FORCEPROP 2 LAST $SEC 1
J 0
(-1125 1575);
DISPLAY 0.680851 (-1125 1575);
PAINT MONO (-1125 1575);
DISPLAY INVISIBLE (-1125 1575);
FORCEPROP 2 LAST CDS_SEC 1
J 0
(-1125 1575);
DISPLAY 1.021277 (-1125 1575);
DISPLAY INVISIBLE (-1125 1575);
FORCEADD HOLE..1
(-1500 1250);
FORCEPROP 1 LAST PART_NUMBER HOLE1079
J 0
(-1625 1430);
DISPLAY 0.723404 (-1625 1430);
PAINT GREEN (-1625 1430);
DISPLAY INVISIBLE (-1625 1430);
FORCEPROP 1 LAST MATERIAL EMPTY
J 0
(-1625 1385);
DISPLAY 0.723404 (-1625 1385);
PAINT GREEN (-1625 1385);
FORCEPROP 2 LAST PACK_TYPE TH
J 0
(-1625 1525);
DISPLAY 1.021277 (-1625 1525);
FORCEPROP 1 LAST $LOCATION H19
J 0
(-1625 1485);
DISPLAY 0.723404 (-1625 1485);
PAINT GREEN (-1625 1485);
FORCEPROP 2 LASTPIN (-1700 1275) $PN 1
J 2
(-1710 1285);
DISPLAY 0.808511 (-1710 1285);
FORCEPROP 1 LAST PATH I74
J 0
(-1450 1380);
DISPLAY 0.723404 (-1450 1380);
PAINT GREEN (-1450 1380);
DISPLAY INVISIBLE (-1450 1380);
FORCEPROP 1 LAST NEEDS_NO_SIZE TRUE
J 0
(-1500 1250);
DISPLAY 0.468085 (-1500 1250);
PAINT GREEN (-1500 1250);
DISPLAY INVISIBLE (-1500 1250);
FORCEPROP 2 LAST CDS_LIB pure_quanta
J 0
(-1500 1250);
PAINT MONO (-1500 1250);
DISPLAY INVISIBLE (-1500 1250);
FORCEPROP 2 LAST CDS_LOCATION H19
J 0
(-1625 1575);
DISPLAY 1.021277 (-1625 1575);
DISPLAY INVISIBLE (-1625 1575);
FORCEPROP 2 LAST $SEC 1
J 0
(-1625 1575);
DISPLAY 0.680851 (-1625 1575);
PAINT MONO (-1625 1575);
DISPLAY INVISIBLE (-1625 1575);
FORCEPROP 2 LAST CDS_SEC 1
J 0
(-1625 1575);
DISPLAY 1.021277 (-1625 1575);
DISPLAY INVISIBLE (-1625 1575);
FORCEADD HOLE..1
(-2000 1250);
FORCEPROP 1 LAST PART_NUMBER HOLE1079
J 0
(-2125 1430);
DISPLAY 0.723404 (-2125 1430);
PAINT GREEN (-2125 1430);
DISPLAY INVISIBLE (-2125 1430);
FORCEPROP 2 LAST PACK_TYPE TH
J 0
(-2125 1525);
DISPLAY 1.021277 (-2125 1525);
FORCEPROP 1 LAST MATERIAL EMPTY
J 0
(-2125 1385);
DISPLAY 0.723404 (-2125 1385);
PAINT GREEN (-2125 1385);
FORCEPROP 1 LAST $LOCATION H17
J 0
(-2125 1485);
DISPLAY 0.723404 (-2125 1485);
PAINT GREEN (-2125 1485);
FORCEPROP 2 LASTPIN (-2200 1275) $PN 1
J 2
(-2210 1285);
DISPLAY 0.808511 (-2210 1285);
FORCEPROP 1 LAST PATH I75
J 0
(-1950 1380);
DISPLAY 0.723404 (-1950 1380);
PAINT GREEN (-1950 1380);
DISPLAY INVISIBLE (-1950 1380);
FORCEPROP 1 LAST NEEDS_NO_SIZE TRUE
J 0
(-2000 1250);
DISPLAY 0.468085 (-2000 1250);
PAINT GREEN (-2000 1250);
DISPLAY INVISIBLE (-2000 1250);
FORCEPROP 2 LAST CDS_LIB pure_quanta
J 0
(-2000 1250);
PAINT MONO (-2000 1250);
DISPLAY INVISIBLE (-2000 1250);
FORCEPROP 2 LAST CDS_LOCATION H17
J 0
(-2125 1575);
DISPLAY 1.021277 (-2125 1575);
DISPLAY INVISIBLE (-2125 1575);
FORCEPROP 2 LAST $SEC 1
J 0
(-2125 1575);
DISPLAY 0.680851 (-2125 1575);
PAINT MONO (-2125 1575);
DISPLAY INVISIBLE (-2125 1575);
FORCEPROP 2 LAST CDS_SEC 1
J 0
(-2125 1575);
DISPLAY 1.021277 (-2125 1575);
DISPLAY INVISIBLE (-2125 1575);
FORCEADD HOLE..1
(1300 2275);
FORCEPROP 1 LAST PART_NUMBER DUMMY50
J 0
(1175 2455);
DISPLAY 0.723404 (1175 2455);
PAINT GREEN (1175 2455);
DISPLAY INVISIBLE (1175 2455);
FORCEPROP 2 LAST PACK_TYPE TH
J 0
(1175 2550);
DISPLAY 1.021277 (1175 2550);
FORCEPROP 1 LAST MATERIAL EMPTY
J 0
(1175 2410);
DISPLAY 0.723404 (1175 2410);
PAINT GREEN (1175 2410);
FORCEPROP 1 LAST $LOCATION H29
J 0
(1175 2510);
DISPLAY 0.723404 (1175 2510);
PAINT GREEN (1175 2510);
FORCEPROP 2 LASTPIN (1100 2300) $PN 1
J 2
(1090 2310);
DISPLAY 0.808511 (1090 2310);
FORCEPROP 1 LAST PATH I8
J 0
(1350 2405);
DISPLAY 0.723404 (1350 2405);
PAINT GREEN (1350 2405);
DISPLAY INVISIBLE (1350 2405);
FORCEPROP 1 LAST NEEDS_NO_SIZE TRUE
J 0
(1300 2275);
DISPLAY 0.468085 (1300 2275);
PAINT GREEN (1300 2275);
DISPLAY INVISIBLE (1300 2275);
FORCEPROP 2 LAST CDS_LIB pure_quanta
J 0
(1300 2275);
PAINT MONO (1300 2275);
DISPLAY INVISIBLE (1300 2275);
FORCEPROP 2 LAST CDS_LOCATION H29
J 0
(1175 2600);
DISPLAY 1.021277 (1175 2600);
DISPLAY INVISIBLE (1175 2600);
FORCEPROP 2 LAST $SEC 1
J 0
(1175 2600);
DISPLAY 0.680851 (1175 2600);
PAINT MONO (1175 2600);
DISPLAY INVISIBLE (1175 2600);
FORCEPROP 2 LAST CDS_SEC 1
J 0
(1175 2600);
DISPLAY 1.021277 (1175 2600);
DISPLAY INVISIBLE (1175 2600);
FORCEADD HOLE..1
(-2500 1250);
FORCEPROP 1 LAST PART_NUMBER HOLE1079
J 0
(-2625 1430);
DISPLAY 0.723404 (-2625 1430);
PAINT GREEN (-2625 1430);
DISPLAY INVISIBLE (-2625 1430);
FORCEPROP 2 LAST PACK_TYPE TH
J 0
(-2625 1525);
DISPLAY 1.021277 (-2625 1525);
FORCEPROP 1 LAST MATERIAL EMPTY
J 0
(-2625 1385);
DISPLAY 0.723404 (-2625 1385);
PAINT GREEN (-2625 1385);
FORCEPROP 1 LAST $LOCATION H15
J 0
(-2625 1485);
DISPLAY 0.723404 (-2625 1485);
PAINT GREEN (-2625 1485);
FORCEPROP 2 LASTPIN (-2700 1275) $PN 1
J 2
(-2710 1285);
DISPLAY 0.808511 (-2710 1285);
FORCEPROP 1 LAST PATH I83
J 0
(-2450 1380);
DISPLAY 0.723404 (-2450 1380);
PAINT GREEN (-2450 1380);
DISPLAY INVISIBLE (-2450 1380);
FORCEPROP 2 LAST CDS_LIB pure_quanta
J 0
(-2500 1250);
PAINT MONO (-2500 1250);
DISPLAY INVISIBLE (-2500 1250);
FORCEPROP 1 LAST NEEDS_NO_SIZE TRUE
J 0
(-2500 1250);
DISPLAY 0.468085 (-2500 1250);
PAINT GREEN (-2500 1250);
DISPLAY INVISIBLE (-2500 1250);
FORCEPROP 2 LAST CDS_LOCATION H15
J 0
(-2625 1575);
DISPLAY 1.021277 (-2625 1575);
DISPLAY INVISIBLE (-2625 1575);
FORCEPROP 2 LAST $SEC 1
J 0
(-2625 1575);
DISPLAY 0.680851 (-2625 1575);
PAINT MONO (-2625 1575);
DISPLAY INVISIBLE (-2625 1575);
FORCEPROP 2 LAST CDS_SEC 1
J 0
(-2625 1575);
DISPLAY 1.021277 (-2625 1575);
DISPLAY INVISIBLE (-2625 1575);
FORCEADD HOLE..1
(1325 1050);
FORCEPROP 1 LAST PART_NUMBER HOLE1187
J 0
(1200 1230);
DISPLAY 0.723404 (1200 1230);
PAINT GREEN (1200 1230);
DISPLAY INVISIBLE (1200 1230);
FORCEPROP 1 LAST MATERIAL EMPTY
J 0
(1200 1185);
DISPLAY 0.723404 (1200 1185);
PAINT GREEN (1200 1185);
FORCEPROP 2 LAST PACK_TYPE TH
J 0
(1200 1325);
DISPLAY 1.021277 (1200 1325);
FORCEPROP 1 LAST $LOCATION H77
J 0
(1200 1285);
DISPLAY 0.723404 (1200 1285);
PAINT GREEN (1200 1285);
FORCEPROP 0 LASTPIN (1125 1075) $PN 1
J 2
(1115 1085);
DISPLAY 0.680851 (1115 1085);
PAINT MONO (1115 1085);
FORCEPROP 2 LAST CDS_LIB pure_quanta
J 0
(1325 1050);
DISPLAY INVISIBLE (1325 1050);
FORCEPROP 1 LAST NEEDS_NO_SIZE TRUE
J 0
(1325 1050);
DISPLAY 0.468085 (1325 1050);
PAINT GREEN (1325 1050);
DISPLAY INVISIBLE (1325 1050);
FORCEPROP 1 LAST PATH I87
J 0
(1375 1180);
DISPLAY 0.723404 (1375 1180);
PAINT GREEN (1375 1180);
DISPLAY INVISIBLE (1375 1180);
FORCEPROP 0 LAST CDS_LOCATION H77
J 0
(1200 1375);
DISPLAY 1.021277 (1200 1375);
DISPLAY INVISIBLE (1200 1375);
FORCEPROP 0 LAST $SEC 1
J 0
(1200 1375);
DISPLAY 0.680851 (1200 1375);
PAINT MONO (1200 1375);
DISPLAY INVISIBLE (1200 1375);
FORCEPROP 0 LAST CDS_SEC 1
J 0
(1200 1375);
DISPLAY 1.021277 (1200 1375);
DISPLAY INVISIBLE (1200 1375);
FORCEADD HOLE..1
(3600 1175);
FORCEPROP 1 LAST PART_NUMBER TMP-Q_HOLE78
J 0
(3475 1355);
DISPLAY 0.723404 (3475 1355);
PAINT GREEN (3475 1355);
DISPLAY INVISIBLE (3475 1355);
FORCEPROP 1 LAST MATERIAL EMPTY
J 0
(3475 1310);
DISPLAY 0.723404 (3475 1310);
PAINT GREEN (3475 1310);
FORCEPROP 2 LAST PACK_TYPE TH
J 0
(3475 1450);
DISPLAY 1.021277 (3475 1450);
FORCEPROP 1 LAST $LOCATION H38
J 0
(3475 1410);
DISPLAY 0.723404 (3475 1410);
PAINT GREEN (3475 1410);
FORCEPROP 2 LASTPIN (3400 1200) $PN 1
J 2
(3390 1210);
DISPLAY 0.808511 (3390 1210);
FORCEPROP 1 LAST PATH I9
J 0
(3650 1305);
DISPLAY 0.723404 (3650 1305);
PAINT GREEN (3650 1305);
DISPLAY INVISIBLE (3650 1305);
FORCEPROP 1 LAST NEEDS_NO_SIZE TRUE
J 0
(3600 1175);
DISPLAY 0.468085 (3600 1175);
PAINT GREEN (3600 1175);
DISPLAY INVISIBLE (3600 1175);
FORCEPROP 2 LAST CDS_LIB pure_quanta
J 0
(3600 1175);
PAINT MONO (3600 1175);
DISPLAY INVISIBLE (3600 1175);
FORCEPROP 2 LAST CDS_LOCATION H38
J 0
(3475 1500);
DISPLAY 1.021277 (3475 1500);
DISPLAY INVISIBLE (3475 1500);
FORCEPROP 2 LAST $SEC 1
J 0
(3475 1500);
DISPLAY 0.680851 (3475 1500);
PAINT MONO (3475 1500);
DISPLAY INVISIBLE (3475 1500);
FORCEPROP 2 LAST CDS_SEC 1
J 0
(3475 1500);
DISPLAY 1.021277 (3475 1500);
DISPLAY INVISIBLE (3475 1500);
FORCEADD QUANTA_TITLE_BLOCK_C..1
(6150 -1375);
FORCEPROP 0 LAST CDS_CON_LAST_MODIFIED Fri Aug 25 14:05:32 2023
J 0
(4265 -1360);
PAINT MONO (4265 -1360);
DISPLAY INVISIBLE (4265 -1360);
FORCEPROP 2 LAST CUSTOM_TXT_CDS <XR_PAGE_TITLE>
J 0
(-1740 3875);
DISPLAY 0.638298 (-1740 3875);
PAINT PINK (-1740 3875);
DISPLAY INVISIBLE (-1740 3875);
FORCEPROP 2 LAST CUSTOM_TXT_CDS <CON_LAST_MODIFIED>
J 0
(4265 -1360);
DISPLAY 0.978723 (4265 -1360);
FORCEPROP 2 LAST CUSTOM_TXT_CDS <Q_PROJ>
J 0
(3768 -1273);
DISPLAY 1.212766 (3768 -1273);
FORCEPROP 2 LAST CUSTOM_TXT_CDS <Q_NUMBER>
J 0
(4747 -1272);
DISPLAY 1.212766 (4747 -1272);
FORCEPROP 2 LAST CUSTOM_TXT_CDS <Q_REV>
J 0
(5966 -1272);
DISPLAY 1.212766 (5966 -1272);
FORCEPROP 2 LAST CUSTOM_TXT_CDS <CON_PAGE_NUM> OF <CON_TOTAL_PAGES>
J 0
(5704 -1357);
DISPLAY 0.978723 (5704 -1357);
FORCEPROP 2 LAST CUSTOM_TXT_CDS <NAME_1>
J 0
(2975 -1200);
FORCEPROP 2 LAST CUSTOM_TXT_CDS <NAME_2>
J 0
(2975 -1325);
FORCEPROP 1 LAST Q_TITLE MOUNTING HOLE
J 0
(-3216 -1349);
DISPLAY 2.446809 (-3216 -1349);
PAINT GREEN (-3216 -1349);
FORCEPROP 1 LAST Q_DEPT 
J 1
(2387 -1326);
DISPLAY 1.957447 (2387 -1326);
PAINT GREEN (2387 -1326);
FORCEPROP 2 LAST CDS_XR_PAGE_TITLE CR-310 : @S9S_MB_2U_LIB.S9S_MB_2U(SCH_1):PAGE310
J 0
(-1740 3875);
DISPLAY 0.638298 (-1740 3875);
PAINT PINK (-1740 3875);
DISPLAY INVISIBLE (-1740 3875);
FORCEPROP 1 LAST COMMENT_BODY TRUE
J 0
(6162 -1388);
DISPLAY 0.978723 (6162 -1388);
PAINT GREEN (6162 -1388);
DISPLAY INVISIBLE (6162 -1388);
FORCEPROP 2 LAST PAGE_BORDER TRUE
J 0
(-1740 3875);
DISPLAY 0.638298 (-1740 3875);
PAINT PINK (-1740 3875);
DISPLAY INVISIBLE (-1740 3875);
FORCEPROP 1 LAST CDS_LMAN_SYM_OUTLINE -9475,6775,100,-125
J 0
(6150 -1375);
DISPLAY 0.468085 (6150 -1375);
PAINT GREEN (6150 -1375);
DISPLAY INVISIBLE (6150 -1375);
FORCEPROP 2 LAST CDS_LIB pure_quanta
J 0
(6150 -1375);
PAINT MONO (6150 -1375);
DISPLAY INVISIBLE (6150 -1375);
WIRE 16 -1 (1075 -875)(1075 -800);
WIRE 16 -1 (50 -875)(50 -800);
WIRE 16 -1 (-725 -875)(-725 -800);
WIRE 16 -1 (5125 1050)(5125 1175);
WIRE 16 -1 (1050 950)(1050 1075);
WIRE 16 -1 (-2600 -875)(-2600 -800);
WIRE 16 -1 (-1825 -875)(-1825 -800);
WIRE 16 -1 (3600 2050)(3600 2175);
WIRE 16 -1 (4100 2050)(4100 2175);
WIRE 16 -1 (-1450 2150)(-1450 2275);
WIRE 16 -1 (-800 2150)(-800 2275);
WIRE 16 -1 (-2100 2150)(-2100 2275);
WIRE 16 -1 (-2725 2150)(-2725 2275);
WIRE 16 -1 (1350 4450)(1350 4100);
WIRE 16 -1 (1350 4450)(1425 4450);
WIRE 16 -1 (650 4425)(650 4075);
WIRE 16 -1 (650 4425)(725 4425);
WIRE 16 -1 (-25 4425)(-25 4075);
WIRE 16 -1 (-25 4425)(50 4425);
WIRE 16 -1 (-700 4425)(-700 4075);
WIRE 16 -1 (-700 4425)(-625 4425);
WIRE 16 -1 (-1375 4075)(-1375 4425);
WIRE 16 -1 (-2050 4075)(-2050 4425);
WIRE 16 -1 (-2750 4425)(-2750 4075);
WIRE 16 -1 (-2750 4425)(-2675 4425);
WIRE 16 -1 (1350 3575)(1350 3225);
WIRE 16 -1 (1350 3575)(1425 3575);
WIRE 16 -1 (650 3550)(650 3125);
WIRE 16 -1 (650 3550)(725 3550);
WIRE 16 -1 (-25 3125)(-25 3550);
WIRE 16 -1 (-700 3550)(-700 3125);
WIRE 16 -1 (-700 3550)(-625 3550);
WIRE 16 -1 (-1375 3125)(-1375 3550);
WIRE 16 -1 (-2050 3550)(-2050 3125);
WIRE 16 -1 (-2050 3550)(-1975 3550);
WIRE 16 -1 (2025 4100)(2025 4450);
WIRE 16 -1 (2025 3225)(2025 3575);
WIRE 16 -1 (2750 3225)(2750 3575);
WIRE 16 -1 (2750 4450)(2750 4100);
WIRE 16 -1 (2750 4450)(2825 4450);
WIRE 16 -1 (-2750 3550)(-2750 3200);
WIRE 16 -1 (-2750 3550)(-2675 3550);
WIRE 16 -1 (500 950)(500 1075);
WIRE 16 -1 (3400 4450)(3400 4100);
WIRE 16 -1 (3400 4450)(3475 4450);
WIRE 16 -1 (4075 4100)(4075 4450);
WIRE 16 -1 (3400 3575)(3400 3225);
WIRE 16 -1 (3400 3575)(3475 3575);
WIRE 16 -1 (500 1075)(575 1075);
WIRE 16 -1 (1050 1075)(1125 1075);
WIRE 16 -1 (-2050 4425)(-1975 4425);
WIRE 16 -1 (-1375 4425)(-1300 4425);
WIRE 16 -1 (2025 4450)(2100 4450);
WIRE 16 -1 (2025 3575)(2100 3575);
WIRE 16 -1 (-25 3550)(50 3550);
WIRE 16 -1 (-1375 3550)(-1300 3550);
WIRE 16 -1 (2750 3575)(2825 3575);
WIRE 16 -1 (1550 -525)(1625 -525);
WIRE 16 -1 (1625 -800)(1625 -525);
WIRE 16 -1 (1450 -800)(1450 -725);
WIRE 16 -1 (1450 -800)(1625 -800);
WIRE 16 -1 (1350 -800)(1450 -800);
WIRE 16 -1 (1350 -800)(1350 -725);
WIRE 16 -1 (1625 -525)(1625 -425);
WIRE 16 -1 (1550 -425)(1625 -425);
WIRE 16 -1 (1625 -250)(1625 -425);
WIRE 16 -1 (1250 -800)(1250 -725);
WIRE 16 -1 (1250 -800)(1350 -800);
WIRE 16 -1 (1075 -800)(1250 -800);
WIRE 16 -1 (1350 -325)(1350 -250);
WIRE 16 -1 (1350 -250)(1625 -250);
WIRE 16 -1 (1075 -250)(1350 -250);
WIRE 16 -1 (1075 -525)(1075 -800);
WIRE 16 -1 (1075 -525)(1150 -525);
WIRE 16 -1 (1075 -425)(1075 -525);
WIRE 16 -1 (1075 -425)(1075 -250);
WIRE 16 -1 (1075 -425)(1150 -425);
WIRE 16 -1 (-2125 -425)(-2050 -425);
WIRE 16 -1 (-2050 -250)(-2050 -425);
WIRE 16 -1 (-2125 -525)(-2050 -525);
WIRE 16 -1 (-2050 -525)(-2050 -425);
WIRE 16 -1 (-2325 -325)(-2325 -250);
WIRE 16 -1 (-2325 -250)(-2050 -250);
WIRE 16 -1 (-2600 -250)(-2325 -250);
WIRE 16 -1 (-2050 -800)(-2050 -525);
WIRE 16 -1 (-2225 -800)(-2050 -800);
WIRE 16 -1 (-2225 -800)(-2225 -725);
WIRE 16 -1 (-2600 -425)(-2600 -250);
WIRE 16 -1 (-2600 -425)(-2525 -425);
WIRE 16 -1 (-2600 -425)(-2600 -525);
WIRE 16 -1 (-2600 -525)(-2525 -525);
WIRE 16 -1 (-2325 -800)(-2325 -725);
WIRE 16 -1 (-2325 -800)(-2225 -800);
WIRE 16 -1 (-2425 -800)(-2325 -800);
WIRE 16 -1 (-2425 -800)(-2425 -725);
WIRE 16 -1 (-2600 -525)(-2600 -800);
WIRE 16 -1 (-2600 -800)(-2425 -800);
WIRE 16 -1 (-1350 -525)(-1275 -525);
WIRE 16 -1 (-1275 -800)(-1275 -525);
WIRE 16 -1 (-1450 -800)(-1450 -725);
WIRE 16 -1 (-1450 -800)(-1275 -800);
WIRE 16 -1 (-1550 -800)(-1550 -725);
WIRE 16 -1 (-1550 -800)(-1450 -800);
WIRE 16 -1 (-1275 -525)(-1275 -425);
WIRE 16 -1 (-1350 -425)(-1275 -425);
WIRE 16 -1 (-1275 -250)(-1275 -425);
WIRE 16 -1 (-1650 -800)(-1550 -800);
WIRE 16 -1 (-1650 -800)(-1650 -725);
WIRE 16 -1 (-1825 -800)(-1650 -800);
WIRE 16 -1 (-1550 -325)(-1550 -250);
WIRE 16 -1 (-1550 -250)(-1275 -250);
WIRE 16 -1 (-1825 -250)(-1550 -250);
WIRE 16 -1 (-1825 -525)(-1825 -800);
WIRE 16 -1 (-1825 -525)(-1750 -525);
WIRE 16 -1 (-1825 -425)(-1825 -525);
WIRE 16 -1 (-1825 -425)(-1825 -250);
WIRE 16 -1 (-1825 -425)(-1750 -425);
WIRE 16 -1 (-2725 2275)(-2650 2275);
WIRE 16 -1 (-2100 2275)(-2025 2275);
WIRE 16 -1 (-1450 2275)(-1375 2275);
WIRE 16 -1 (-800 2275)(-725 2275);
WIRE 16 -1 (4075 4450)(4150 4450);
WIRE 16 -1 (525 -525)(600 -525);
WIRE 16 -1 (600 -800)(600 -525);
WIRE 16 -1 (425 -800)(425 -725);
WIRE 16 -1 (425 -800)(600 -800);
WIRE 16 -1 (325 -800)(425 -800);
WIRE 16 -1 (325 -800)(325 -725);
WIRE 16 -1 (600 -525)(600 -425);
WIRE 16 -1 (525 -425)(600 -425);
WIRE 16 -1 (600 -250)(600 -425);
WIRE 16 -1 (225 -800)(225 -725);
WIRE 16 -1 (225 -800)(325 -800);
WIRE 16 -1 (50 -800)(225 -800);
WIRE 16 -1 (325 -325)(325 -250);
WIRE 16 -1 (325 -250)(600 -250);
WIRE 16 -1 (50 -250)(325 -250);
WIRE 16 -1 (50 -525)(50 -800);
WIRE 16 -1 (50 -525)(125 -525);
WIRE 16 -1 (50 -425)(50 -525);
WIRE 16 -1 (50 -425)(50 -250);
WIRE 16 -1 (50 -425)(125 -425);
WIRE 16 -1 (-250 -525)(-175 -525);
WIRE 16 -1 (-175 -800)(-175 -525);
WIRE 16 -1 (-350 -800)(-350 -725);
WIRE 16 -1 (-350 -800)(-175 -800);
WIRE 16 -1 (-450 -800)(-350 -800);
WIRE 16 -1 (-450 -800)(-450 -725);
WIRE 16 -1 (-175 -525)(-175 -425);
WIRE 16 -1 (-250 -425)(-175 -425);
WIRE 16 -1 (-175 -250)(-175 -425);
WIRE 16 -1 (-550 -800)(-550 -725);
WIRE 16 -1 (-550 -800)(-450 -800);
WIRE 16 -1 (-725 -800)(-550 -800);
WIRE 16 -1 (-450 -325)(-450 -250);
WIRE 16 -1 (-450 -250)(-175 -250);
WIRE 16 -1 (-725 -250)(-450 -250);
WIRE 16 -1 (-725 -525)(-725 -800);
WIRE 16 -1 (-725 -525)(-650 -525);
WIRE 16 -1 (-725 -425)(-725 -525);
WIRE 16 -1 (-725 -425)(-725 -250);
WIRE 16 -1 (-725 -425)(-650 -425);
WIRE 16 -1 (5125 1175)(5200 1175);
WIRE 16 -1 (4100 2175)(4175 2175);
WIRE 16 -1 (3600 2175)(3675 2175);
DOT 1 (-2600 -800);
DOT 1 (-2600 -525);
DOT 1 (-2600 -425);
DOT 1 (-2425 -800);
DOT 1 (-2225 -800);
DOT 1 (-2050 -525);
DOT 1 (-2325 -250);
DOT 1 (-2050 -425);
DOT 1 (-1825 -800);
DOT 1 (-1825 -525);
DOT 1 (-1550 -800);
DOT 1 (-1650 -800);
DOT 1 (-1825 -425);
DOT 1 (-1550 -250);
DOT 1 (-1450 -800);
DOT 1 (-1275 -525);
DOT 1 (-1275 -425);
DOT 1 (-2325 -800);
DOT 1 (-725 -800);
DOT 1 (-725 -525);
DOT 1 (-725 -425);
DOT 1 (-550 -800);
DOT 1 (-450 -800);
DOT 1 (-350 -800);
DOT 1 (-175 -525);
DOT 1 (-450 -250);
DOT 1 (-175 -425);
DOT 1 (50 -800);
DOT 1 (50 -525);
DOT 1 (225 -800);
DOT 1 (325 -800);
DOT 1 (50 -425);
DOT 1 (325 -250);
DOT 1 (425 -800);
DOT 1 (600 -525);
DOT 1 (600 -425);
DOT 1 (1075 -800);
DOT 1 (1250 -800);
DOT 1 (1075 -525);
DOT 1 (1450 -800);
DOT 1 (1350 -800);
DOT 1 (1075 -425);
DOT 1 (1350 -250);
DOT 1 (1625 -525);
DOT 1 (1625 -425);
FORCENOTE
HOLE1187 (E1S SCREW HOLE)
(575 1600) 0;
DISPLAY LEFT (575 1600);
DISPLAY 1.276596 (575 1600);
PAINT GREEN (575 1600);
FORCENOTE
HOLE_R4-2X5D2B4_IX0-1T_NPM_RB
(575 1725) 0;
DISPLAY LEFT (575 1725);
DISPLAY 1.595745 (575 1725);
PAINT SKYBLUE (575 1725);
FORCENOTE
HOLE39(GUIDE PIN)
(4975 4450) 0;
DISPLAY LEFT (4975 4450);
DISPLAY 1.276596 (4975 4450);
PAINT GREEN (4975 4450);
FORCENOTE
HOLE1247(M.2)
(2250 2775) 0;
DISPLAY LEFT (2250 2775);
DISPLAY 1.276596 (2250 2775);
PAINT GREEN (2250 2775);
FORCENOTE
TOOLING HOLE
(75 2675) 0;
DISPLAY LEFT (75 2675);
DISPLAY 1.276596 (75 2675);
PAINT WHITE (75 2675);
FORCENOTE
GND_HOLE149
(-2700 5000) 0;
DISPLAY LEFT (-2700 5000);
DISPLAY 1.276596 (-2700 5000);
PAINT GREEN (-2700 5000);
FORCENOTE
GND_C10_D4
(-2700 5100) 0;
DISPLAY LEFT (-2700 5100);
DISPLAY 1.595745 (-2700 5100);
PAINT SKYBLUE (-2700 5100);
FORCENOTE
HOLE_D3-429N
(-2750 1825) 0;
DISPLAY LEFT (-2750 1825);
DISPLAY 1.595745 (-2750 1825);
PAINT SKYBLUE (-2750 1825);
FORCENOTE
GND_C8D4B8
(-700 75) 0;
DISPLAY LEFT (-700 75);
DISPLAY 1.276596 (-700 75);
PAINT GREEN (-700 75);
FORCENOTE
HOLE1199(MOS HS)
(-2675 2675) 0;
DISPLAY LEFT (-2675 2675);
DISPLAY 1.276596 (-2675 2675);
PAINT GREEN (-2675 2675);
FORCENOTE
G_HOLE_C8D3-2B8I5_RO6_NPB
(-2675 2800) 0;
DISPLAY LEFT (-2675 2800);
DISPLAY 1.595745 (-2675 2800);
PAINT SKYBLUE (-2675 2800);
FORCENOTE
MODULE HOLE
(4800 1575) 0;
DISPLAY LEFT (4800 1575);
DISPLAY 1.276596 (4800 1575);
PAINT GREEN (4800 1575);
FORCENOTE
HOLE_C8D4-2B8_NPM
(4800 1675) 0;
DISPLAY LEFT (4800 1675);
DISPLAY 1.276596 (4800 1675);
PAINT GREEN (4800 1675);
FORCENOTE
HOLE_DUMMY50
(75 2800) 0;
DISPLAY LEFT (75 2800);
DISPLAY 1.595745 (75 2800);
PAINT SKYBLUE (75 2800);
FORCENOTE
GND_HOLE140 (HANDLE)
(-2550 75) 0;
DISPLAY LEFT (-2550 75);
DISPLAY 1.276596 (-2550 75);
PAINT GREEN (-2550 75);
FORCENOTE
HOLE1079 (CPU SOCKET HOLE)
(-2750 1725) 0;
DISPLAY LEFT (-2750 1725);
DISPLAY 1.276596 (-2750 1725);
PAINT GREEN (-2750 1725);
FORCENOTE
HOLE300 (CPU HS HOLE)
(2650 -350) 0;
DISPLAY LEFT (2650 -350);
DISPLAY 1.276596 (2650 -350);
PAINT GREEN (2650 -350);
FORCENOTE
HOLE_D10N
(2650 -225) 0;
DISPLAY LEFT (2650 -225);
DISPLAY 1.595745 (2650 -225);
PAINT SKYBLUE (2650 -225);
FORCENOTE
HOLE_OB6-4X8OBD3-2X4-8B6-4X8N_RO6X7-6_NPM
(2250 2875) 0;
DISPLAY LEFT (2250 2875);
DISPLAY 1.595745 (2250 2875);
PAINT SKYBLUE (2250 2875);
FORCENOTE
HOLE_C4-5D3-8B8I5-6_RO6-6_NPT_RB
(3600 2700) 0;
DISPLAY LEFT (3600 2700);
DISPLAY 1.595745 (3600 2700);
PAINT SKYBLUE (3600 2700);
FORCENOTE
HOLE1248 (M.2 LATCH HOLE)
(3600 2575) 0;
DISPLAY LEFT (3600 2575);
DISPLAY 1.276596 (3600 2575);
PAINT GREEN (3600 2575);
FORCENOTE
GND_HOLE514(STD)
(1075 100) 0;
DISPLAY LEFT (1075 100);
DISPLAY 1.276596 (1075 100);
PAINT GREEN (1075 100);
FORCENOTE
HOLE78 (PCH HEATSINK HOLE)
(2900 1600) 0;
DISPLAY LEFT (2900 1600);
DISPLAY 1.276596 (2900 1600);
PAINT GREEN (2900 1600);
FORCENOTE
HOLE_D3-1N
(2900 1725) 0;
DISPLAY LEFT (2900 1725);
DISPLAY 1.595745 (2900 1725);
PAINT SKYBLUE (2900 1725);
QUIT
